FILE_TYPE = MACRO_DRAWING;
SET COLOR_WIRE YELLOW;
SET COLOR_PROP MONO;
SET COLOR_DOT WHITE;
SET COLOR_ARC YELLOW;
SET COLOR_BODY GREEN;
SET COLOR_NOTE MONO;
SET PROP_DISPLAY VALUE;
SET PAGE_NUMBER P50;
FORCEADD GND..1
R 2
(5950 750);
FORCEPROP 3 LASTPIN (5950 800) SIG_NAME GND\g
J 0
(5960 810);
DISPLAY 0.659574 (5960 810);
PAINT MONO (5960 810);
DISPLAY INVISIBLE (5960 810);
FORCEPROP 1 LAST VOLTAGE 0
J 0
(5950 750);
PAINT SKYBLUE (5950 750);
DISPLAY INVISIBLE (5950 750);
FORCEPROP 2 LAST BOM_COST MEM
J 0
(5950 755);
PAINT ORANGE (5950 755);
DISPLAY INVISIBLE (5950 755);
FORCEPROP 2 LAST CDS_LIB mstr_symbols
J 0
(5950 750);
DISPLAY 0.787234 (5950 750);
PAINT MONO (5950 750);
DISPLAY INVISIBLE (5950 750);
FORCEPROP 1 LAST SIZE 1B
J 2
(5875 700);
DISPLAY 1.170213 (5875 700);
PAINT GREEN (5875 700);
DISPLAY INVISIBLE (5875 700);
FORCEPROP 1 LAST BODY_TYPE PLUMBING
J 2
(5995 707);
DISPLAY 0.340426 (5995 707);
PAINT GREEN (5995 707);
DISPLAY INVISIBLE (5995 707);
FORCEPROP 1 LAST PATH I1
J 2
(5875 750);
DISPLAY 0.872340 (5875 750);
PAINT AQUA (5875 750);
DISPLAY INVISIBLE (5875 750);
FORCEPROP 2 LAST ROOM DDR4_CH_B
J 0
(5950 755);
PAINT ORANGE (5950 755);
DISPLAY INVISIBLE (5950 755);
FORCEPROP 1 LAST HDL_POWER GND
J 2
(5950 900);
DISPLAY 0.553191 (5950 900);
PAINT GREEN (5950 900);
DISPLAY INVISIBLE (5950 900);
FORCEADD TAP..6
R 2
(4350 4350);
FORCEPROP 3 LASTPIN (4300 4350) SIG_NAME M_D_DQS_DN<13>
J 0
(4310 4360);
DISPLAY 0.659574 (4310 4360);
PAINT MONO (4310 4360);
DISPLAY INVISIBLE (4310 4360);
FORCEPROP 1 LASTPIN (4300 4350) BN 13
J 2
(4350 4360);
DISPLAY 0.617021 (4350 4360);
PAINT PINK (4350 4360);
FORCEPROP 2 LAST CDS_LIB mstr_standard
J 0
(4350 4350);
DISPLAY 0.787234 (4350 4350);
PAINT MONO (4350 4350);
DISPLAY INVISIBLE (4350 4350);
FORCEPROP 1 LAST BODY_TYPE PLUMBING
J 2
(4350 4300);
DISPLAY 1.234043 (4350 4300);
PAINT GREEN (4350 4300);
DISPLAY INVISIBLE (4350 4300);
FORCEPROP 1 LAST HDL_TAP TRUE
J 2
(4025 4225);
DISPLAY 1.234043 (4025 4225);
PAINT GREEN (4025 4225);
DISPLAY INVISIBLE (4025 4225);
FORCEPROP 1 LAST PATH I10
J 2
(4352 4350);
DISPLAY 0.872340 (4352 4350);
PAINT GREEN (4352 4350);
DISPLAY INVISIBLE (4352 4350);
FORCEADD TAP..6
R 2
(1700 3050);
FORCEPROP 3 LASTPIN (1650 3050) SIG_NAME M_D_DQ<29>
J 0
(1660 3060);
DISPLAY 0.659574 (1660 3060);
PAINT MONO (1660 3060);
DISPLAY INVISIBLE (1660 3060);
FORCEPROP 1 LASTPIN (1650 3050) BN 29
J 2
(1700 3060);
DISPLAY 0.617021 (1700 3060);
PAINT PINK (1700 3060);
FORCEPROP 2 LAST CDS_LIB mstr_standard
J 2
(1700 3050);
DISPLAY 0.787234 (1700 3050);
PAINT MONO (1700 3050);
DISPLAY INVISIBLE (1700 3050);
FORCEPROP 1 LAST BODY_TYPE PLUMBING
J 2
(1700 3000);
DISPLAY 1.234043 (1700 3000);
PAINT GREEN (1700 3000);
DISPLAY INVISIBLE (1700 3000);
FORCEPROP 1 LAST HDL_TAP TRUE
J 2
(1375 2925);
DISPLAY 1.234043 (1375 2925);
PAINT GREEN (1375 2925);
DISPLAY INVISIBLE (1375 2925);
FORCEPROP 1 LAST PATH I100
J 2
(1702 3050);
DISPLAY 0.872340 (1702 3050);
PAINT GREEN (1702 3050);
DISPLAY INVISIBLE (1702 3050);
FORCEADD TAP..6
R 2
(1700 2850);
FORCEPROP 3 LASTPIN (1650 2850) SIG_NAME M_D_DQ<25>
J 0
(1660 2860);
DISPLAY 0.659574 (1660 2860);
PAINT MONO (1660 2860);
DISPLAY INVISIBLE (1660 2860);
FORCEPROP 1 LASTPIN (1650 2850) BN 25
J 2
(1700 2860);
DISPLAY 0.617021 (1700 2860);
PAINT PINK (1700 2860);
FORCEPROP 2 LAST CDS_LIB mstr_standard
J 2
(1700 2850);
DISPLAY 0.787234 (1700 2850);
PAINT MONO (1700 2850);
DISPLAY INVISIBLE (1700 2850);
FORCEPROP 1 LAST BODY_TYPE PLUMBING
J 2
(1700 2800);
DISPLAY 1.234043 (1700 2800);
PAINT GREEN (1700 2800);
DISPLAY INVISIBLE (1700 2800);
FORCEPROP 1 LAST HDL_TAP TRUE
J 2
(1375 2725);
DISPLAY 1.234043 (1375 2725);
PAINT GREEN (1375 2725);
DISPLAY INVISIBLE (1375 2725);
FORCEPROP 1 LAST PATH I101
J 2
(1702 2850);
DISPLAY 0.872340 (1702 2850);
PAINT GREEN (1702 2850);
DISPLAY INVISIBLE (1702 2850);
FORCEADD TAP..6
R 2
(1700 2800);
FORCEPROP 3 LASTPIN (1650 2800) SIG_NAME M_D_DQ<24>
J 0
(1660 2810);
DISPLAY 0.659574 (1660 2810);
PAINT MONO (1660 2810);
DISPLAY INVISIBLE (1660 2810);
FORCEPROP 1 LASTPIN (1650 2800) BN 24
J 2
(1700 2810);
DISPLAY 0.617021 (1700 2810);
PAINT PINK (1700 2810);
FORCEPROP 2 LAST CDS_LIB mstr_standard
J 2
(1700 2800);
DISPLAY 0.787234 (1700 2800);
PAINT MONO (1700 2800);
DISPLAY INVISIBLE (1700 2800);
FORCEPROP 1 LAST BODY_TYPE PLUMBING
J 2
(1700 2750);
DISPLAY 1.234043 (1700 2750);
PAINT GREEN (1700 2750);
DISPLAY INVISIBLE (1700 2750);
FORCEPROP 1 LAST HDL_TAP TRUE
J 2
(1375 2675);
DISPLAY 1.234043 (1375 2675);
PAINT GREEN (1375 2675);
DISPLAY INVISIBLE (1375 2675);
FORCEPROP 1 LAST PATH I102
J 2
(1702 2800);
DISPLAY 0.872340 (1702 2800);
PAINT GREEN (1702 2800);
DISPLAY INVISIBLE (1702 2800);
FORCEADD TAP..6
R 2
(1700 2900);
FORCEPROP 3 LASTPIN (1650 2900) SIG_NAME M_D_DQ<26>
J 0
(1660 2910);
DISPLAY 0.659574 (1660 2910);
PAINT MONO (1660 2910);
DISPLAY INVISIBLE (1660 2910);
FORCEPROP 1 LASTPIN (1650 2900) BN 26
J 2
(1700 2910);
DISPLAY 0.617021 (1700 2910);
PAINT PINK (1700 2910);
FORCEPROP 2 LAST CDS_LIB mstr_standard
J 2
(1700 2900);
DISPLAY 0.787234 (1700 2900);
PAINT MONO (1700 2900);
DISPLAY INVISIBLE (1700 2900);
FORCEPROP 1 LAST BODY_TYPE PLUMBING
J 2
(1700 2850);
DISPLAY 1.234043 (1700 2850);
PAINT GREEN (1700 2850);
DISPLAY INVISIBLE (1700 2850);
FORCEPROP 1 LAST HDL_TAP TRUE
J 2
(1375 2775);
DISPLAY 1.234043 (1375 2775);
PAINT GREEN (1375 2775);
DISPLAY INVISIBLE (1375 2775);
FORCEPROP 1 LAST PATH I103
J 2
(1702 2900);
DISPLAY 0.872340 (1702 2900);
PAINT GREEN (1702 2900);
DISPLAY INVISIBLE (1702 2900);
FORCEADD TAP..6
R 2
(1700 2950);
FORCEPROP 3 LASTPIN (1650 2950) SIG_NAME M_D_DQ<27>
J 0
(1660 2960);
DISPLAY 0.659574 (1660 2960);
PAINT MONO (1660 2960);
DISPLAY INVISIBLE (1660 2960);
FORCEPROP 1 LASTPIN (1650 2950) BN 27
J 2
(1700 2960);
DISPLAY 0.617021 (1700 2960);
PAINT PINK (1700 2960);
FORCEPROP 2 LAST CDS_LIB mstr_standard
J 2
(1700 2950);
DISPLAY 0.787234 (1700 2950);
PAINT MONO (1700 2950);
DISPLAY INVISIBLE (1700 2950);
FORCEPROP 1 LAST BODY_TYPE PLUMBING
J 2
(1700 2900);
DISPLAY 1.234043 (1700 2900);
PAINT GREEN (1700 2900);
DISPLAY INVISIBLE (1700 2900);
FORCEPROP 1 LAST HDL_TAP TRUE
J 2
(1375 2825);
DISPLAY 1.234043 (1375 2825);
PAINT GREEN (1375 2825);
DISPLAY INVISIBLE (1375 2825);
FORCEPROP 1 LAST PATH I104
J 2
(1702 2950);
DISPLAY 0.872340 (1702 2950);
PAINT GREEN (1702 2950);
DISPLAY INVISIBLE (1702 2950);
FORCEADD TAP..6
R 2
(1700 3000);
FORCEPROP 3 LASTPIN (1650 3000) SIG_NAME M_D_DQ<28>
J 0
(1660 3010);
DISPLAY 0.659574 (1660 3010);
PAINT MONO (1660 3010);
DISPLAY INVISIBLE (1660 3010);
FORCEPROP 1 LASTPIN (1650 3000) BN 28
J 2
(1700 3010);
DISPLAY 0.617021 (1700 3010);
PAINT PINK (1700 3010);
FORCEPROP 2 LAST CDS_LIB mstr_standard
J 2
(1700 3000);
DISPLAY 0.787234 (1700 3000);
PAINT MONO (1700 3000);
DISPLAY INVISIBLE (1700 3000);
FORCEPROP 1 LAST BODY_TYPE PLUMBING
J 2
(1700 2950);
DISPLAY 1.234043 (1700 2950);
PAINT GREEN (1700 2950);
DISPLAY INVISIBLE (1700 2950);
FORCEPROP 1 LAST HDL_TAP TRUE
J 2
(1375 2875);
DISPLAY 1.234043 (1375 2875);
PAINT GREEN (1375 2875);
DISPLAY INVISIBLE (1375 2875);
FORCEPROP 1 LAST PATH I105
J 2
(1702 3000);
DISPLAY 0.872340 (1702 3000);
PAINT GREEN (1702 3000);
DISPLAY INVISIBLE (1702 3000);
FORCEADD TAP..6
R 2
(1700 2650);
FORCEPROP 3 LASTPIN (1650 2650) SIG_NAME M_D_DQ<21>
J 0
(1660 2660);
DISPLAY 0.659574 (1660 2660);
PAINT MONO (1660 2660);
DISPLAY INVISIBLE (1660 2660);
FORCEPROP 1 LASTPIN (1650 2650) BN 21
J 2
(1700 2660);
DISPLAY 0.617021 (1700 2660);
PAINT PINK (1700 2660);
FORCEPROP 2 LAST CDS_LIB mstr_standard
J 2
(1700 2650);
DISPLAY 0.787234 (1700 2650);
PAINT MONO (1700 2650);
DISPLAY INVISIBLE (1700 2650);
FORCEPROP 1 LAST BODY_TYPE PLUMBING
J 2
(1700 2600);
DISPLAY 1.234043 (1700 2600);
PAINT GREEN (1700 2600);
DISPLAY INVISIBLE (1700 2600);
FORCEPROP 1 LAST HDL_TAP TRUE
J 2
(1375 2525);
DISPLAY 1.234043 (1375 2525);
PAINT GREEN (1375 2525);
DISPLAY INVISIBLE (1375 2525);
FORCEPROP 1 LAST PATH I106
J 2
(1702 2650);
DISPLAY 0.872340 (1702 2650);
PAINT GREEN (1702 2650);
DISPLAY INVISIBLE (1702 2650);
FORCEADD TAP..6
R 2
(1700 2600);
FORCEPROP 3 LASTPIN (1650 2600) SIG_NAME M_D_DQ<20>
J 0
(1660 2610);
DISPLAY 0.659574 (1660 2610);
PAINT MONO (1660 2610);
DISPLAY INVISIBLE (1660 2610);
FORCEPROP 1 LASTPIN (1650 2600) BN 20
J 2
(1700 2610);
DISPLAY 0.617021 (1700 2610);
PAINT PINK (1700 2610);
FORCEPROP 2 LAST CDS_LIB mstr_standard
J 2
(1700 2600);
DISPLAY 0.787234 (1700 2600);
PAINT MONO (1700 2600);
DISPLAY INVISIBLE (1700 2600);
FORCEPROP 1 LAST BODY_TYPE PLUMBING
J 2
(1700 2550);
DISPLAY 1.234043 (1700 2550);
PAINT GREEN (1700 2550);
DISPLAY INVISIBLE (1700 2550);
FORCEPROP 1 LAST HDL_TAP TRUE
J 2
(1375 2475);
DISPLAY 1.234043 (1375 2475);
PAINT GREEN (1375 2475);
DISPLAY INVISIBLE (1375 2475);
FORCEPROP 1 LAST PATH I107
J 2
(1702 2600);
DISPLAY 0.872340 (1702 2600);
PAINT GREEN (1702 2600);
DISPLAY INVISIBLE (1702 2600);
FORCEADD TAP..6
R 2
(1700 2550);
FORCEPROP 3 LASTPIN (1650 2550) SIG_NAME M_D_DQ<19>
J 0
(1660 2560);
DISPLAY 0.659574 (1660 2560);
PAINT MONO (1660 2560);
DISPLAY INVISIBLE (1660 2560);
FORCEPROP 1 LASTPIN (1650 2550) BN 19
J 2
(1700 2560);
DISPLAY 0.617021 (1700 2560);
PAINT PINK (1700 2560);
FORCEPROP 2 LAST CDS_LIB mstr_standard
J 2
(1700 2550);
DISPLAY 0.787234 (1700 2550);
PAINT MONO (1700 2550);
DISPLAY INVISIBLE (1700 2550);
FORCEPROP 1 LAST BODY_TYPE PLUMBING
J 2
(1700 2500);
DISPLAY 1.234043 (1700 2500);
PAINT GREEN (1700 2500);
DISPLAY INVISIBLE (1700 2500);
FORCEPROP 1 LAST HDL_TAP TRUE
J 2
(1375 2425);
DISPLAY 1.234043 (1375 2425);
PAINT GREEN (1375 2425);
DISPLAY INVISIBLE (1375 2425);
FORCEPROP 1 LAST PATH I108
J 2
(1702 2550);
DISPLAY 0.872340 (1702 2550);
PAINT GREEN (1702 2550);
DISPLAY INVISIBLE (1702 2550);
FORCEADD TAP..6
R 2
(1700 2700);
FORCEPROP 3 LASTPIN (1650 2700) SIG_NAME M_D_DQ<22>
J 0
(1660 2710);
DISPLAY 0.659574 (1660 2710);
PAINT MONO (1660 2710);
DISPLAY INVISIBLE (1660 2710);
FORCEPROP 1 LASTPIN (1650 2700) BN 22
J 2
(1700 2710);
DISPLAY 0.617021 (1700 2710);
PAINT PINK (1700 2710);
FORCEPROP 2 LAST CDS_LIB mstr_standard
J 2
(1700 2700);
DISPLAY 0.787234 (1700 2700);
PAINT MONO (1700 2700);
DISPLAY INVISIBLE (1700 2700);
FORCEPROP 1 LAST BODY_TYPE PLUMBING
J 2
(1700 2650);
DISPLAY 1.234043 (1700 2650);
PAINT GREEN (1700 2650);
DISPLAY INVISIBLE (1700 2650);
FORCEPROP 1 LAST HDL_TAP TRUE
J 2
(1375 2575);
DISPLAY 1.234043 (1375 2575);
PAINT GREEN (1375 2575);
DISPLAY INVISIBLE (1375 2575);
FORCEPROP 1 LAST PATH I109
J 2
(1702 2700);
DISPLAY 0.872340 (1702 2700);
PAINT GREEN (1702 2700);
DISPLAY INVISIBLE (1702 2700);
FORCEADD TAP..6
R 2
(4350 4450);
FORCEPROP 3 LASTPIN (4300 4450) SIG_NAME M_D_DQS_DN<14>
J 0
(4310 4460);
DISPLAY 0.659574 (4310 4460);
PAINT MONO (4310 4460);
DISPLAY INVISIBLE (4310 4460);
FORCEPROP 1 LASTPIN (4300 4450) BN 14
J 2
(4350 4460);
DISPLAY 0.617021 (4350 4460);
PAINT PINK (4350 4460);
FORCEPROP 2 LAST CDS_LIB mstr_standard
J 0
(4350 4450);
DISPLAY 0.787234 (4350 4450);
PAINT MONO (4350 4450);
DISPLAY INVISIBLE (4350 4450);
FORCEPROP 1 LAST BODY_TYPE PLUMBING
J 2
(4350 4400);
DISPLAY 1.234043 (4350 4400);
PAINT GREEN (4350 4400);
DISPLAY INVISIBLE (4350 4400);
FORCEPROP 1 LAST HDL_TAP TRUE
J 2
(4025 4325);
DISPLAY 1.234043 (4025 4325);
PAINT GREEN (4025 4325);
DISPLAY INVISIBLE (4025 4325);
FORCEPROP 1 LAST PATH I11
J 2
(4352 4450);
DISPLAY 0.872340 (4352 4450);
PAINT GREEN (4352 4450);
DISPLAY INVISIBLE (4352 4450);
FORCEADD TAP..6
R 2
(1700 2750);
FORCEPROP 3 LASTPIN (1650 2750) SIG_NAME M_D_DQ<23>
J 0
(1660 2760);
DISPLAY 0.659574 (1660 2760);
PAINT MONO (1660 2760);
DISPLAY INVISIBLE (1660 2760);
FORCEPROP 1 LASTPIN (1650 2750) BN 23
J 2
(1700 2760);
DISPLAY 0.617021 (1700 2760);
PAINT PINK (1700 2760);
FORCEPROP 2 LAST CDS_LIB mstr_standard
J 2
(1700 2750);
DISPLAY 0.787234 (1700 2750);
PAINT MONO (1700 2750);
DISPLAY INVISIBLE (1700 2750);
FORCEPROP 1 LAST BODY_TYPE PLUMBING
J 2
(1700 2700);
DISPLAY 1.234043 (1700 2700);
PAINT GREEN (1700 2700);
DISPLAY INVISIBLE (1700 2700);
FORCEPROP 1 LAST HDL_TAP TRUE
J 2
(1375 2625);
DISPLAY 1.234043 (1375 2625);
PAINT GREEN (1375 2625);
DISPLAY INVISIBLE (1375 2625);
FORCEPROP 1 LAST PATH I110
J 2
(1702 2750);
DISPLAY 0.872340 (1702 2750);
PAINT GREEN (1702 2750);
DISPLAY INVISIBLE (1702 2750);
FORCEADD TAP..6
R 2
(1700 2300);
FORCEPROP 3 LASTPIN (1650 2300) SIG_NAME M_D_DQ<14>
J 0
(1660 2310);
DISPLAY 0.659574 (1660 2310);
PAINT MONO (1660 2310);
DISPLAY INVISIBLE (1660 2310);
FORCEPROP 1 LASTPIN (1650 2300) BN 14
J 2
(1700 2310);
DISPLAY 0.617021 (1700 2310);
PAINT PINK (1700 2310);
FORCEPROP 2 LAST CDS_LIB mstr_standard
J 2
(1700 2300);
DISPLAY 0.787234 (1700 2300);
PAINT MONO (1700 2300);
DISPLAY INVISIBLE (1700 2300);
FORCEPROP 1 LAST BODY_TYPE PLUMBING
J 2
(1700 2250);
DISPLAY 1.234043 (1700 2250);
PAINT GREEN (1700 2250);
DISPLAY INVISIBLE (1700 2250);
FORCEPROP 1 LAST HDL_TAP TRUE
J 2
(1375 2175);
DISPLAY 1.234043 (1375 2175);
PAINT GREEN (1375 2175);
DISPLAY INVISIBLE (1375 2175);
FORCEPROP 1 LAST PATH I111
J 2
(1702 2300);
DISPLAY 0.872340 (1702 2300);
PAINT GREEN (1702 2300);
DISPLAY INVISIBLE (1702 2300);
FORCEADD TAP..6
R 2
(1700 2350);
FORCEPROP 3 LASTPIN (1650 2350) SIG_NAME M_D_DQ<15>
J 0
(1660 2360);
DISPLAY 0.659574 (1660 2360);
PAINT MONO (1660 2360);
DISPLAY INVISIBLE (1660 2360);
FORCEPROP 1 LASTPIN (1650 2350) BN 15
J 2
(1700 2360);
DISPLAY 0.617021 (1700 2360);
PAINT PINK (1700 2360);
FORCEPROP 2 LAST CDS_LIB mstr_standard
J 2
(1700 2350);
DISPLAY 0.787234 (1700 2350);
PAINT MONO (1700 2350);
DISPLAY INVISIBLE (1700 2350);
FORCEPROP 1 LAST BODY_TYPE PLUMBING
J 2
(1700 2300);
DISPLAY 1.234043 (1700 2300);
PAINT GREEN (1700 2300);
DISPLAY INVISIBLE (1700 2300);
FORCEPROP 1 LAST HDL_TAP TRUE
J 2
(1375 2225);
DISPLAY 1.234043 (1375 2225);
PAINT GREEN (1375 2225);
DISPLAY INVISIBLE (1375 2225);
FORCEPROP 1 LAST PATH I112
J 2
(1702 2350);
DISPLAY 0.872340 (1702 2350);
PAINT GREEN (1702 2350);
DISPLAY INVISIBLE (1702 2350);
FORCEADD TAP..6
R 2
(1700 2400);
FORCEPROP 3 LASTPIN (1650 2400) SIG_NAME M_D_DQ<16>
J 0
(1660 2410);
DISPLAY 0.659574 (1660 2410);
PAINT MONO (1660 2410);
DISPLAY INVISIBLE (1660 2410);
FORCEPROP 1 LASTPIN (1650 2400) BN 16
J 2
(1700 2410);
DISPLAY 0.617021 (1700 2410);
PAINT PINK (1700 2410);
FORCEPROP 2 LAST CDS_LIB mstr_standard
J 2
(1700 2400);
DISPLAY 0.787234 (1700 2400);
PAINT MONO (1700 2400);
DISPLAY INVISIBLE (1700 2400);
FORCEPROP 1 LAST BODY_TYPE PLUMBING
J 2
(1700 2350);
DISPLAY 1.234043 (1700 2350);
PAINT GREEN (1700 2350);
DISPLAY INVISIBLE (1700 2350);
FORCEPROP 1 LAST HDL_TAP TRUE
J 2
(1375 2275);
DISPLAY 1.234043 (1375 2275);
PAINT GREEN (1375 2275);
DISPLAY INVISIBLE (1375 2275);
FORCEPROP 1 LAST PATH I113
J 2
(1702 2400);
DISPLAY 0.872340 (1702 2400);
PAINT GREEN (1702 2400);
DISPLAY INVISIBLE (1702 2400);
FORCEADD TAP..6
R 2
(1700 2500);
FORCEPROP 3 LASTPIN (1650 2500) SIG_NAME M_D_DQ<18>
J 0
(1660 2510);
DISPLAY 0.659574 (1660 2510);
PAINT MONO (1660 2510);
DISPLAY INVISIBLE (1660 2510);
FORCEPROP 1 LASTPIN (1650 2500) BN 18
J 2
(1700 2510);
DISPLAY 0.617021 (1700 2510);
PAINT PINK (1700 2510);
FORCEPROP 2 LAST CDS_LIB mstr_standard
J 2
(1700 2500);
DISPLAY 0.787234 (1700 2500);
PAINT MONO (1700 2500);
DISPLAY INVISIBLE (1700 2500);
FORCEPROP 1 LAST BODY_TYPE PLUMBING
J 2
(1700 2450);
DISPLAY 1.234043 (1700 2450);
PAINT GREEN (1700 2450);
DISPLAY INVISIBLE (1700 2450);
FORCEPROP 1 LAST HDL_TAP TRUE
J 2
(1375 2375);
DISPLAY 1.234043 (1375 2375);
PAINT GREEN (1375 2375);
DISPLAY INVISIBLE (1375 2375);
FORCEPROP 1 LAST PATH I114
J 2
(1702 2500);
DISPLAY 0.872340 (1702 2500);
PAINT GREEN (1702 2500);
DISPLAY INVISIBLE (1702 2500);
FORCEADD TAP..6
R 2
(1700 2450);
FORCEPROP 3 LASTPIN (1650 2450) SIG_NAME M_D_DQ<17>
J 0
(1660 2460);
DISPLAY 0.659574 (1660 2460);
PAINT MONO (1660 2460);
DISPLAY INVISIBLE (1660 2460);
FORCEPROP 1 LASTPIN (1650 2450) BN 17
J 2
(1700 2460);
DISPLAY 0.617021 (1700 2460);
PAINT PINK (1700 2460);
FORCEPROP 2 LAST CDS_LIB mstr_standard
J 2
(1700 2450);
DISPLAY 0.787234 (1700 2450);
PAINT MONO (1700 2450);
DISPLAY INVISIBLE (1700 2450);
FORCEPROP 1 LAST BODY_TYPE PLUMBING
J 2
(1700 2400);
DISPLAY 1.234043 (1700 2400);
PAINT GREEN (1700 2400);
DISPLAY INVISIBLE (1700 2400);
FORCEPROP 1 LAST HDL_TAP TRUE
J 2
(1375 2325);
DISPLAY 1.234043 (1375 2325);
PAINT GREEN (1375 2325);
DISPLAY INVISIBLE (1375 2325);
FORCEPROP 1 LAST PATH I115
J 2
(1702 2450);
DISPLAY 0.872340 (1702 2450);
PAINT GREEN (1702 2450);
DISPLAY INVISIBLE (1702 2450);
FORCEADD TAP..6
R 2
(1700 2100);
FORCEPROP 3 LASTPIN (1650 2100) SIG_NAME M_D_DQ<10>
J 0
(1660 2110);
DISPLAY 0.659574 (1660 2110);
PAINT MONO (1660 2110);
DISPLAY INVISIBLE (1660 2110);
FORCEPROP 1 LASTPIN (1650 2100) BN 10
J 2
(1700 2110);
DISPLAY 0.617021 (1700 2110);
PAINT PINK (1700 2110);
FORCEPROP 2 LAST CDS_LIB mstr_standard
J 2
(1700 2100);
DISPLAY 0.787234 (1700 2100);
PAINT MONO (1700 2100);
DISPLAY INVISIBLE (1700 2100);
FORCEPROP 1 LAST BODY_TYPE PLUMBING
J 2
(1700 2050);
DISPLAY 1.234043 (1700 2050);
PAINT GREEN (1700 2050);
DISPLAY INVISIBLE (1700 2050);
FORCEPROP 1 LAST HDL_TAP TRUE
J 2
(1375 1975);
DISPLAY 1.234043 (1375 1975);
PAINT GREEN (1375 1975);
DISPLAY INVISIBLE (1375 1975);
FORCEPROP 1 LAST PATH I116
J 2
(1702 2100);
DISPLAY 0.872340 (1702 2100);
PAINT GREEN (1702 2100);
DISPLAY INVISIBLE (1702 2100);
FORCEADD TAP..6
R 2
(1700 2050);
FORCEPROP 3 LASTPIN (1650 2050) SIG_NAME M_D_DQ<9>
J 0
(1660 2060);
DISPLAY 0.659574 (1660 2060);
PAINT MONO (1660 2060);
DISPLAY INVISIBLE (1660 2060);
FORCEPROP 1 LASTPIN (1650 2050) BN 9
J 2
(1700 2060);
DISPLAY 0.617021 (1700 2060);
PAINT PINK (1700 2060);
FORCEPROP 2 LAST CDS_LIB mstr_standard
J 2
(1700 2050);
DISPLAY 0.787234 (1700 2050);
PAINT MONO (1700 2050);
DISPLAY INVISIBLE (1700 2050);
FORCEPROP 1 LAST BODY_TYPE PLUMBING
J 2
(1700 2000);
DISPLAY 1.234043 (1700 2000);
PAINT GREEN (1700 2000);
DISPLAY INVISIBLE (1700 2000);
FORCEPROP 1 LAST HDL_TAP TRUE
J 2
(1375 1925);
DISPLAY 1.234043 (1375 1925);
PAINT GREEN (1375 1925);
DISPLAY INVISIBLE (1375 1925);
FORCEPROP 1 LAST PATH I117
J 2
(1702 2050);
DISPLAY 0.872340 (1702 2050);
PAINT GREEN (1702 2050);
DISPLAY INVISIBLE (1702 2050);
FORCEADD TAP..6
R 2
(1700 2150);
FORCEPROP 3 LASTPIN (1650 2150) SIG_NAME M_D_DQ<11>
J 0
(1660 2160);
DISPLAY 0.659574 (1660 2160);
PAINT MONO (1660 2160);
DISPLAY INVISIBLE (1660 2160);
FORCEPROP 1 LASTPIN (1650 2150) BN 11
J 2
(1700 2160);
DISPLAY 0.617021 (1700 2160);
PAINT PINK (1700 2160);
FORCEPROP 2 LAST CDS_LIB mstr_standard
J 2
(1700 2150);
DISPLAY 0.787234 (1700 2150);
PAINT MONO (1700 2150);
DISPLAY INVISIBLE (1700 2150);
FORCEPROP 1 LAST BODY_TYPE PLUMBING
J 2
(1700 2100);
DISPLAY 1.234043 (1700 2100);
PAINT GREEN (1700 2100);
DISPLAY INVISIBLE (1700 2100);
FORCEPROP 1 LAST HDL_TAP TRUE
J 2
(1375 2025);
DISPLAY 1.234043 (1375 2025);
PAINT GREEN (1375 2025);
DISPLAY INVISIBLE (1375 2025);
FORCEPROP 1 LAST PATH I118
J 2
(1702 2150);
DISPLAY 0.872340 (1702 2150);
PAINT GREEN (1702 2150);
DISPLAY INVISIBLE (1702 2150);
FORCEADD TAP..6
R 2
(1700 2200);
FORCEPROP 3 LASTPIN (1650 2200) SIG_NAME M_D_DQ<12>
J 0
(1660 2210);
DISPLAY 0.659574 (1660 2210);
PAINT MONO (1660 2210);
DISPLAY INVISIBLE (1660 2210);
FORCEPROP 1 LASTPIN (1650 2200) BN 12
J 2
(1700 2210);
DISPLAY 0.617021 (1700 2210);
PAINT PINK (1700 2210);
FORCEPROP 2 LAST CDS_LIB mstr_standard
J 2
(1700 2200);
DISPLAY 0.787234 (1700 2200);
PAINT MONO (1700 2200);
DISPLAY INVISIBLE (1700 2200);
FORCEPROP 1 LAST BODY_TYPE PLUMBING
J 2
(1700 2150);
DISPLAY 1.234043 (1700 2150);
PAINT GREEN (1700 2150);
DISPLAY INVISIBLE (1700 2150);
FORCEPROP 1 LAST HDL_TAP TRUE
J 2
(1375 2075);
DISPLAY 1.234043 (1375 2075);
PAINT GREEN (1375 2075);
DISPLAY INVISIBLE (1375 2075);
FORCEPROP 1 LAST PATH I119
J 2
(1702 2200);
DISPLAY 0.872340 (1702 2200);
PAINT GREEN (1702 2200);
DISPLAY INVISIBLE (1702 2200);
FORCEADD TAP..6
R 2
(4350 4250);
FORCEPROP 3 LASTPIN (4300 4250) SIG_NAME M_D_DQS_DN<12>
J 0
(4310 4260);
DISPLAY 0.659574 (4310 4260);
PAINT MONO (4310 4260);
DISPLAY INVISIBLE (4310 4260);
FORCEPROP 1 LASTPIN (4300 4250) BN 12
J 2
(4350 4260);
DISPLAY 0.617021 (4350 4260);
PAINT PINK (4350 4260);
FORCEPROP 2 LAST CDS_LIB mstr_standard
J 0
(4350 4250);
DISPLAY 0.787234 (4350 4250);
PAINT MONO (4350 4250);
DISPLAY INVISIBLE (4350 4250);
FORCEPROP 1 LAST BODY_TYPE PLUMBING
J 2
(4350 4200);
DISPLAY 1.234043 (4350 4200);
PAINT GREEN (4350 4200);
DISPLAY INVISIBLE (4350 4200);
FORCEPROP 1 LAST HDL_TAP TRUE
J 2
(4025 4125);
DISPLAY 1.234043 (4025 4125);
PAINT GREEN (4025 4125);
DISPLAY INVISIBLE (4025 4125);
FORCEPROP 1 LAST PATH I12
J 2
(4352 4250);
DISPLAY 0.872340 (4352 4250);
PAINT GREEN (4352 4250);
DISPLAY INVISIBLE (4352 4250);
FORCEADD TAP..6
R 2
(1700 2250);
FORCEPROP 3 LASTPIN (1650 2250) SIG_NAME M_D_DQ<13>
J 0
(1660 2260);
DISPLAY 0.659574 (1660 2260);
PAINT MONO (1660 2260);
DISPLAY INVISIBLE (1660 2260);
FORCEPROP 1 LASTPIN (1650 2250) BN 13
J 2
(1700 2260);
DISPLAY 0.617021 (1700 2260);
PAINT PINK (1700 2260);
FORCEPROP 2 LAST CDS_LIB mstr_standard
J 2
(1700 2250);
DISPLAY 0.787234 (1700 2250);
PAINT MONO (1700 2250);
DISPLAY INVISIBLE (1700 2250);
FORCEPROP 1 LAST BODY_TYPE PLUMBING
J 2
(1700 2200);
DISPLAY 1.234043 (1700 2200);
PAINT GREEN (1700 2200);
DISPLAY INVISIBLE (1700 2200);
FORCEPROP 1 LAST HDL_TAP TRUE
J 2
(1375 2125);
DISPLAY 1.234043 (1375 2125);
PAINT GREEN (1375 2125);
DISPLAY INVISIBLE (1375 2125);
FORCEPROP 1 LAST PATH I120
J 2
(1702 2250);
DISPLAY 0.872340 (1702 2250);
PAINT GREEN (1702 2250);
DISPLAY INVISIBLE (1702 2250);
FORCEADD TAP..6
(200 4050);
FORCEPROP 3 LASTPIN (250 4050) SIG_NAME M_D_MA<3>
J 0
(260 4060);
DISPLAY 0.659574 (260 4060);
PAINT MONO (260 4060);
DISPLAY INVISIBLE (260 4060);
FORCEPROP 1 LASTPIN (250 4050) BN 3
J 0
(200 4060);
DISPLAY 0.617021 (200 4060);
PAINT PINK (200 4060);
FORCEPROP 2 LAST CDS_LIB mstr_standard
J 2
(200 4050);
DISPLAY 0.787234 (200 4050);
PAINT MONO (200 4050);
DISPLAY INVISIBLE (200 4050);
FORCEPROP 1 LAST BODY_TYPE PLUMBING
J 0
(200 4000);
DISPLAY 1.234043 (200 4000);
PAINT GREEN (200 4000);
DISPLAY INVISIBLE (200 4000);
FORCEPROP 1 LAST HDL_TAP TRUE
J 0
(525 3925);
DISPLAY 1.234043 (525 3925);
PAINT GREEN (525 3925);
DISPLAY INVISIBLE (525 3925);
FORCEPROP 1 LAST PATH I121
J 0
(198 4050);
DISPLAY 0.872340 (198 4050);
PAINT GREEN (198 4050);
DISPLAY INVISIBLE (198 4050);
FORCEADD TAP..6
(200 3900);
FORCEPROP 3 LASTPIN (250 3900) SIG_NAME M_D_MA<0>
J 0
(260 3910);
DISPLAY 0.659574 (260 3910);
PAINT MONO (260 3910);
DISPLAY INVISIBLE (260 3910);
FORCEPROP 1 LASTPIN (250 3900) BN 0
J 0
(200 3910);
DISPLAY 0.617021 (200 3910);
PAINT PINK (200 3910);
FORCEPROP 2 LAST CDS_LIB mstr_standard
J 2
(200 3900);
DISPLAY 0.787234 (200 3900);
PAINT MONO (200 3900);
DISPLAY INVISIBLE (200 3900);
FORCEPROP 1 LAST BODY_TYPE PLUMBING
J 0
(200 3850);
DISPLAY 1.234043 (200 3850);
PAINT GREEN (200 3850);
DISPLAY INVISIBLE (200 3850);
FORCEPROP 1 LAST HDL_TAP TRUE
J 0
(525 3775);
DISPLAY 1.234043 (525 3775);
PAINT GREEN (525 3775);
DISPLAY INVISIBLE (525 3775);
FORCEPROP 1 LAST PATH I122
J 0
(198 3900);
DISPLAY 0.872340 (198 3900);
PAINT GREEN (198 3900);
DISPLAY INVISIBLE (198 3900);
FORCEADD TAP..6
(200 3950);
FORCEPROP 3 LASTPIN (250 3950) SIG_NAME M_D_MA<1>
J 0
(260 3960);
DISPLAY 0.659574 (260 3960);
PAINT MONO (260 3960);
DISPLAY INVISIBLE (260 3960);
FORCEPROP 1 LASTPIN (250 3950) BN 1
J 0
(200 3960);
DISPLAY 0.617021 (200 3960);
PAINT PINK (200 3960);
FORCEPROP 2 LAST CDS_LIB mstr_standard
J 2
(200 3950);
DISPLAY 0.787234 (200 3950);
PAINT MONO (200 3950);
DISPLAY INVISIBLE (200 3950);
FORCEPROP 1 LAST BODY_TYPE PLUMBING
J 0
(200 3900);
DISPLAY 1.234043 (200 3900);
PAINT GREEN (200 3900);
DISPLAY INVISIBLE (200 3900);
FORCEPROP 1 LAST HDL_TAP TRUE
J 0
(525 3825);
DISPLAY 1.234043 (525 3825);
PAINT GREEN (525 3825);
DISPLAY INVISIBLE (525 3825);
FORCEPROP 1 LAST PATH I123
J 0
(198 3950);
DISPLAY 0.872340 (198 3950);
PAINT GREEN (198 3950);
DISPLAY INVISIBLE (198 3950);
FORCEADD TAP..6
(200 4000);
FORCEPROP 3 LASTPIN (250 4000) SIG_NAME M_D_MA<2>
J 0
(260 4010);
DISPLAY 0.659574 (260 4010);
PAINT MONO (260 4010);
DISPLAY INVISIBLE (260 4010);
FORCEPROP 1 LASTPIN (250 4000) BN 2
J 0
(200 4010);
DISPLAY 0.617021 (200 4010);
PAINT PINK (200 4010);
FORCEPROP 2 LAST CDS_LIB mstr_standard
J 2
(200 4000);
DISPLAY 0.787234 (200 4000);
PAINT MONO (200 4000);
DISPLAY INVISIBLE (200 4000);
FORCEPROP 1 LAST BODY_TYPE PLUMBING
J 0
(200 3950);
DISPLAY 1.234043 (200 3950);
PAINT GREEN (200 3950);
DISPLAY INVISIBLE (200 3950);
FORCEPROP 1 LAST HDL_TAP TRUE
J 0
(525 3875);
DISPLAY 1.234043 (525 3875);
PAINT GREEN (525 3875);
DISPLAY INVISIBLE (525 3875);
FORCEPROP 1 LAST PATH I124
J 0
(198 4000);
DISPLAY 0.872340 (198 4000);
PAINT GREEN (198 4000);
DISPLAY INVISIBLE (198 4000);
FORCEADD TAP..6
(200 3800);
FORCEPROP 3 LASTPIN (250 3800) SIG_NAME M_D_BA<1>
J 0
(260 3810);
DISPLAY 0.659574 (260 3810);
PAINT MONO (260 3810);
DISPLAY INVISIBLE (260 3810);
FORCEPROP 1 LASTPIN (250 3800) BN 1
J 0
(200 3810);
DISPLAY 0.617021 (200 3810);
PAINT PINK (200 3810);
FORCEPROP 2 LAST CDS_LIB mstr_standard
J 0
(200 3800);
DISPLAY 0.787234 (200 3800);
PAINT MONO (200 3800);
DISPLAY INVISIBLE (200 3800);
FORCEPROP 1 LAST BODY_TYPE PLUMBING
J 0
(200 3750);
DISPLAY 1.234043 (200 3750);
PAINT GREEN (200 3750);
DISPLAY INVISIBLE (200 3750);
FORCEPROP 1 LAST HDL_TAP TRUE
J 0
(525 3675);
DISPLAY 1.234043 (525 3675);
PAINT GREEN (525 3675);
DISPLAY INVISIBLE (525 3675);
FORCEPROP 1 LAST PATH I125
J 0
(198 3800);
DISPLAY 0.872340 (198 3800);
PAINT GREEN (198 3800);
DISPLAY INVISIBLE (198 3800);
FORCEADD TAP..6
(200 3650);
FORCEPROP 3 LASTPIN (250 3650) SIG_NAME M_D_BG<0>
J 0
(260 3660);
DISPLAY 0.659574 (260 3660);
PAINT MONO (260 3660);
DISPLAY INVISIBLE (260 3660);
FORCEPROP 1 LASTPIN (250 3650) BN 0
J 0
(200 3660);
DISPLAY 0.617021 (200 3660);
PAINT PINK (200 3660);
FORCEPROP 2 LAST CDS_LIB mstr_standard
J 0
(200 3650);
DISPLAY 0.787234 (200 3650);
PAINT MONO (200 3650);
DISPLAY INVISIBLE (200 3650);
FORCEPROP 1 LAST BODY_TYPE PLUMBING
J 0
(200 3600);
DISPLAY 1.234043 (200 3600);
PAINT GREEN (200 3600);
DISPLAY INVISIBLE (200 3600);
FORCEPROP 1 LAST HDL_TAP TRUE
J 0
(525 3525);
DISPLAY 1.234043 (525 3525);
PAINT GREEN (525 3525);
DISPLAY INVISIBLE (525 3525);
FORCEPROP 1 LAST PATH I126
J 0
(198 3650);
DISPLAY 0.872340 (198 3650);
PAINT GREEN (198 3650);
DISPLAY INVISIBLE (198 3650);
FORCEADD TAP..6
(200 3750);
FORCEPROP 3 LASTPIN (250 3750) SIG_NAME M_D_BA<0>
J 0
(260 3760);
DISPLAY 0.659574 (260 3760);
PAINT MONO (260 3760);
DISPLAY INVISIBLE (260 3760);
FORCEPROP 1 LASTPIN (250 3750) BN 0
J 0
(200 3760);
DISPLAY 0.617021 (200 3760);
PAINT PINK (200 3760);
FORCEPROP 2 LAST CDS_LIB mstr_standard
J 0
(200 3750);
DISPLAY 0.787234 (200 3750);
PAINT MONO (200 3750);
DISPLAY INVISIBLE (200 3750);
FORCEPROP 1 LAST BODY_TYPE PLUMBING
J 0
(200 3700);
DISPLAY 1.234043 (200 3700);
PAINT GREEN (200 3700);
DISPLAY INVISIBLE (200 3700);
FORCEPROP 1 LAST HDL_TAP TRUE
J 0
(525 3625);
DISPLAY 1.234043 (525 3625);
PAINT GREEN (525 3625);
DISPLAY INVISIBLE (525 3625);
FORCEPROP 1 LAST PATH I127
J 0
(198 3750);
DISPLAY 0.872340 (198 3750);
PAINT GREEN (198 3750);
DISPLAY INVISIBLE (198 3750);
FORCEADD TAP..6
(200 3700);
FORCEPROP 3 LASTPIN (250 3700) SIG_NAME M_D_BG<1>
J 0
(260 3710);
DISPLAY 0.659574 (260 3710);
PAINT MONO (260 3710);
DISPLAY INVISIBLE (260 3710);
FORCEPROP 1 LASTPIN (250 3700) BN 1
J 0
(200 3710);
DISPLAY 0.617021 (200 3710);
PAINT PINK (200 3710);
FORCEPROP 2 LAST CDS_LIB mstr_standard
J 0
(200 3700);
DISPLAY 0.787234 (200 3700);
PAINT MONO (200 3700);
DISPLAY INVISIBLE (200 3700);
FORCEPROP 1 LAST BODY_TYPE PLUMBING
J 0
(200 3650);
DISPLAY 1.234043 (200 3650);
PAINT GREEN (200 3650);
DISPLAY INVISIBLE (200 3650);
FORCEPROP 1 LAST HDL_TAP TRUE
J 0
(525 3575);
DISPLAY 1.234043 (525 3575);
PAINT GREEN (525 3575);
DISPLAY INVISIBLE (525 3575);
FORCEPROP 1 LAST PATH I128
J 0
(198 3700);
DISPLAY 0.872340 (198 3700);
PAINT GREEN (198 3700);
DISPLAY INVISIBLE (198 3700);
FORCEADD TAP..6
(200 3550);
FORCEPROP 3 LASTPIN (250 3550) SIG_NAME M_D_CLK_DP<3>
J 0
(260 3560);
DISPLAY 0.659574 (260 3560);
PAINT MONO (260 3560);
DISPLAY INVISIBLE (260 3560);
FORCEPROP 1 LASTPIN (250 3550) BN 3
J 0
(200 3560);
DISPLAY 0.617021 (200 3560);
PAINT PINK (200 3560);
FORCEPROP 2 LAST CDS_LIB mstr_standard
J 0
(200 3550);
DISPLAY 0.787234 (200 3550);
PAINT MONO (200 3550);
DISPLAY INVISIBLE (200 3550);
FORCEPROP 1 LAST BODY_TYPE PLUMBING
J 0
(200 3500);
DISPLAY 1.234043 (200 3500);
PAINT GREEN (200 3500);
DISPLAY INVISIBLE (200 3500);
FORCEPROP 1 LAST HDL_TAP TRUE
J 0
(525 3425);
DISPLAY 1.234043 (525 3425);
PAINT GREEN (525 3425);
DISPLAY INVISIBLE (525 3425);
FORCEPROP 1 LAST PATH I129
J 0
(198 3550);
DISPLAY 0.872340 (198 3550);
PAINT GREEN (198 3550);
DISPLAY INVISIBLE (198 3550);
FORCEADD TAP..6
R 2
(4350 4150);
FORCEPROP 3 LASTPIN (4300 4150) SIG_NAME M_D_DQS_DN<11>
J 0
(4310 4160);
DISPLAY 0.659574 (4310 4160);
PAINT MONO (4310 4160);
DISPLAY INVISIBLE (4310 4160);
FORCEPROP 1 LASTPIN (4300 4150) BN 11
J 2
(4350 4160);
DISPLAY 0.617021 (4350 4160);
PAINT PINK (4350 4160);
FORCEPROP 2 LAST CDS_LIB mstr_standard
J 0
(4350 4150);
DISPLAY 0.787234 (4350 4150);
PAINT MONO (4350 4150);
DISPLAY INVISIBLE (4350 4150);
FORCEPROP 1 LAST BODY_TYPE PLUMBING
J 2
(4350 4100);
DISPLAY 1.234043 (4350 4100);
PAINT GREEN (4350 4100);
DISPLAY INVISIBLE (4350 4100);
FORCEPROP 1 LAST HDL_TAP TRUE
J 2
(4025 4025);
DISPLAY 1.234043 (4025 4025);
PAINT GREEN (4025 4025);
DISPLAY INVISIBLE (4025 4025);
FORCEPROP 1 LAST PATH I13
J 2
(4352 4150);
DISPLAY 0.872340 (4352 4150);
PAINT GREEN (4352 4150);
DISPLAY INVISIBLE (4352 4150);
FORCEADD TAP..6
(200 3450);
FORCEPROP 3 LASTPIN (250 3450) SIG_NAME M_D_CLK_DP<2>
J 0
(260 3460);
DISPLAY 0.659574 (260 3460);
PAINT MONO (260 3460);
DISPLAY INVISIBLE (260 3460);
FORCEPROP 1 LASTPIN (250 3450) BN 2
J 0
(200 3460);
DISPLAY 0.617021 (200 3460);
PAINT PINK (200 3460);
FORCEPROP 2 LAST CDS_LIB mstr_standard
J 0
(200 3450);
DISPLAY 0.787234 (200 3450);
PAINT MONO (200 3450);
DISPLAY INVISIBLE (200 3450);
FORCEPROP 1 LAST BODY_TYPE PLUMBING
J 0
(200 3400);
DISPLAY 1.234043 (200 3400);
PAINT GREEN (200 3400);
DISPLAY INVISIBLE (200 3400);
FORCEPROP 1 LAST HDL_TAP TRUE
J 0
(525 3325);
DISPLAY 1.234043 (525 3325);
PAINT GREEN (525 3325);
DISPLAY INVISIBLE (525 3325);
FORCEPROP 1 LAST PATH I130
J 0
(198 3450);
DISPLAY 0.872340 (198 3450);
PAINT GREEN (198 3450);
DISPLAY INVISIBLE (198 3450);
FORCEADD TAP..6
(200 3250);
FORCEPROP 3 LASTPIN (250 3250) SIG_NAME M_D_CS_N<7>
J 0
(260 3260);
DISPLAY 0.659574 (260 3260);
PAINT MONO (260 3260);
DISPLAY INVISIBLE (260 3260);
FORCEPROP 1 LASTPIN (250 3250) BN 7
J 0
(200 3260);
DISPLAY 0.617021 (200 3260);
PAINT PINK (200 3260);
FORCEPROP 2 LAST CDS_LIB mstr_standard
J 0
(200 3250);
DISPLAY 0.787234 (200 3250);
PAINT MONO (200 3250);
DISPLAY INVISIBLE (200 3250);
FORCEPROP 1 LAST BODY_TYPE PLUMBING
J 0
(200 3200);
DISPLAY 1.234043 (200 3200);
PAINT GREEN (200 3200);
DISPLAY INVISIBLE (200 3200);
FORCEPROP 1 LAST HDL_TAP TRUE
J 0
(525 3125);
DISPLAY 1.234043 (525 3125);
PAINT GREEN (525 3125);
DISPLAY INVISIBLE (525 3125);
FORCEPROP 1 LAST PATH I131
J 0
(198 3250);
DISPLAY 0.872340 (198 3250);
PAINT GREEN (198 3250);
DISPLAY INVISIBLE (198 3250);
FORCEADD TAP..6
(200 3200);
FORCEPROP 3 LASTPIN (250 3200) SIG_NAME M_D_CS_N<6>
J 0
(260 3210);
DISPLAY 0.659574 (260 3210);
PAINT MONO (260 3210);
DISPLAY INVISIBLE (260 3210);
FORCEPROP 1 LASTPIN (250 3200) BN 6
J 0
(200 3210);
DISPLAY 0.617021 (200 3210);
PAINT PINK (200 3210);
FORCEPROP 2 LAST CDS_LIB mstr_standard
J 0
(200 3200);
DISPLAY 0.787234 (200 3200);
PAINT MONO (200 3200);
DISPLAY INVISIBLE (200 3200);
FORCEPROP 1 LAST BODY_TYPE PLUMBING
J 0
(200 3150);
DISPLAY 1.234043 (200 3150);
PAINT GREEN (200 3150);
DISPLAY INVISIBLE (200 3150);
FORCEPROP 1 LAST HDL_TAP TRUE
J 0
(525 3075);
DISPLAY 1.234043 (525 3075);
PAINT GREEN (525 3075);
DISPLAY INVISIBLE (525 3075);
FORCEPROP 1 LAST PATH I132
J 0
(198 3200);
DISPLAY 0.872340 (198 3200);
PAINT GREEN (198 3200);
DISPLAY INVISIBLE (198 3200);
FORCEADD TAP..6
(200 3150);
FORCEPROP 3 LASTPIN (250 3150) SIG_NAME M_D_CS_N<5>
J 0
(260 3160);
DISPLAY 0.659574 (260 3160);
PAINT MONO (260 3160);
DISPLAY INVISIBLE (260 3160);
FORCEPROP 1 LASTPIN (250 3150) BN 5
J 0
(200 3160);
DISPLAY 0.617021 (200 3160);
PAINT PINK (200 3160);
FORCEPROP 2 LAST CDS_LIB mstr_standard
J 0
(200 3150);
DISPLAY 0.787234 (200 3150);
PAINT MONO (200 3150);
DISPLAY INVISIBLE (200 3150);
FORCEPROP 1 LAST BODY_TYPE PLUMBING
J 0
(200 3100);
DISPLAY 1.234043 (200 3100);
PAINT GREEN (200 3100);
DISPLAY INVISIBLE (200 3100);
FORCEPROP 1 LAST HDL_TAP TRUE
J 0
(525 3025);
DISPLAY 1.234043 (525 3025);
PAINT GREEN (525 3025);
DISPLAY INVISIBLE (525 3025);
FORCEPROP 1 LAST PATH I133
J 0
(198 3150);
DISPLAY 0.872340 (198 3150);
PAINT GREEN (198 3150);
DISPLAY INVISIBLE (198 3150);
FORCEADD TAP..6
(200 3100);
FORCEPROP 3 LASTPIN (250 3100) SIG_NAME M_D_CS_N<4>
J 0
(260 3110);
DISPLAY 0.659574 (260 3110);
PAINT MONO (260 3110);
DISPLAY INVISIBLE (260 3110);
FORCEPROP 1 LASTPIN (250 3100) BN 4
J 0
(200 3110);
DISPLAY 0.617021 (200 3110);
PAINT PINK (200 3110);
FORCEPROP 2 LAST CDS_LIB mstr_standard
J 0
(200 3100);
DISPLAY 0.787234 (200 3100);
PAINT MONO (200 3100);
DISPLAY INVISIBLE (200 3100);
FORCEPROP 1 LAST BODY_TYPE PLUMBING
J 0
(200 3050);
DISPLAY 1.234043 (200 3050);
PAINT GREEN (200 3050);
DISPLAY INVISIBLE (200 3050);
FORCEPROP 1 LAST HDL_TAP TRUE
J 0
(525 2975);
DISPLAY 1.234043 (525 2975);
PAINT GREEN (525 2975);
DISPLAY INVISIBLE (525 2975);
FORCEPROP 1 LAST PATH I134
J 0
(198 3100);
DISPLAY 0.872340 (198 3100);
PAINT GREEN (198 3100);
DISPLAY INVISIBLE (198 3100);
FORCEADD TAP..6
(0 3500);
FORCEPROP 3 LASTPIN (50 3500) SIG_NAME M_D_CLK_DN<3>
J 0
(60 3510);
DISPLAY 0.659574 (60 3510);
PAINT MONO (60 3510);
DISPLAY INVISIBLE (60 3510);
FORCEPROP 1 LASTPIN (50 3500) BN 3
J 0
(0 3510);
DISPLAY 0.617021 (0 3510);
PAINT PINK (0 3510);
FORCEPROP 2 LAST CDS_LIB mstr_standard
J 0
(0 3500);
DISPLAY 0.787234 (0 3500);
PAINT MONO (0 3500);
DISPLAY INVISIBLE (0 3500);
FORCEPROP 1 LAST BODY_TYPE PLUMBING
J 0
(0 3450);
DISPLAY 1.234043 (0 3450);
PAINT GREEN (0 3450);
DISPLAY INVISIBLE (0 3450);
FORCEPROP 1 LAST HDL_TAP TRUE
J 0
(325 3375);
DISPLAY 1.234043 (325 3375);
PAINT GREEN (325 3375);
DISPLAY INVISIBLE (325 3375);
FORCEPROP 1 LAST PATH I135
J 0
(-2 3500);
DISPLAY 0.872340 (-2 3500);
PAINT GREEN (-2 3500);
DISPLAY INVISIBLE (-2 3500);
FORCEADD TAP..6
(0 3400);
FORCEPROP 3 LASTPIN (50 3400) SIG_NAME M_D_CLK_DN<2>
J 0
(60 3410);
DISPLAY 0.659574 (60 3410);
PAINT MONO (60 3410);
DISPLAY INVISIBLE (60 3410);
FORCEPROP 1 LASTPIN (50 3400) BN 2
J 0
(0 3410);
DISPLAY 0.617021 (0 3410);
PAINT PINK (0 3410);
FORCEPROP 2 LAST CDS_LIB mstr_standard
J 0
(0 3400);
DISPLAY 0.787234 (0 3400);
PAINT MONO (0 3400);
DISPLAY INVISIBLE (0 3400);
FORCEPROP 1 LAST BODY_TYPE PLUMBING
J 0
(0 3350);
DISPLAY 1.234043 (0 3350);
PAINT GREEN (0 3350);
DISPLAY INVISIBLE (0 3350);
FORCEPROP 1 LAST HDL_TAP TRUE
J 0
(325 3275);
DISPLAY 1.234043 (325 3275);
PAINT GREEN (325 3275);
DISPLAY INVISIBLE (325 3275);
FORCEPROP 1 LAST PATH I136
J 0
(-2 3400);
DISPLAY 0.872340 (-2 3400);
PAINT GREEN (-2 3400);
DISPLAY INVISIBLE (-2 3400);
FORCEADD TAP..6
(200 2800);
FORCEPROP 3 LASTPIN (250 2800) SIG_NAME M_D_ODT<2>
J 0
(260 2810);
DISPLAY 0.659574 (260 2810);
PAINT MONO (260 2810);
DISPLAY INVISIBLE (260 2810);
FORCEPROP 1 LASTPIN (250 2800) BN 2
J 0
(200 2810);
DISPLAY 0.617021 (200 2810);
PAINT PINK (200 2810);
FORCEPROP 2 LAST CDS_LIB mstr_standard
J 0
(200 2800);
DISPLAY 0.787234 (200 2800);
PAINT MONO (200 2800);
DISPLAY INVISIBLE (200 2800);
FORCEPROP 1 LAST BODY_TYPE PLUMBING
J 0
(200 2750);
DISPLAY 1.234043 (200 2750);
PAINT GREEN (200 2750);
DISPLAY INVISIBLE (200 2750);
FORCEPROP 1 LAST HDL_TAP TRUE
J 0
(525 2675);
DISPLAY 1.234043 (525 2675);
PAINT GREEN (525 2675);
DISPLAY INVISIBLE (525 2675);
FORCEPROP 1 LAST PATH I137
J 0
(198 2800);
DISPLAY 0.872340 (198 2800);
PAINT GREEN (198 2800);
DISPLAY INVISIBLE (198 2800);
FORCEADD TAP..6
(200 2950);
FORCEPROP 3 LASTPIN (250 2950) SIG_NAME M_D_CKE<2>
J 0
(260 2960);
DISPLAY 0.659574 (260 2960);
PAINT MONO (260 2960);
DISPLAY INVISIBLE (260 2960);
FORCEPROP 1 LASTPIN (250 2950) BN 2
J 0
(200 2960);
DISPLAY 0.617021 (200 2960);
PAINT PINK (200 2960);
FORCEPROP 2 LAST CDS_LIB mstr_standard
J 0
(200 2950);
DISPLAY 0.787234 (200 2950);
PAINT MONO (200 2950);
DISPLAY INVISIBLE (200 2950);
FORCEPROP 1 LAST BODY_TYPE PLUMBING
J 0
(200 2900);
DISPLAY 1.234043 (200 2900);
PAINT GREEN (200 2900);
DISPLAY INVISIBLE (200 2900);
FORCEPROP 1 LAST HDL_TAP TRUE
J 0
(525 2825);
DISPLAY 1.234043 (525 2825);
PAINT GREEN (525 2825);
DISPLAY INVISIBLE (525 2825);
FORCEPROP 1 LAST PATH I138
J 0
(198 2950);
DISPLAY 0.872340 (198 2950);
PAINT GREEN (198 2950);
DISPLAY INVISIBLE (198 2950);
FORCEADD TAP..6
(200 3000);
FORCEPROP 3 LASTPIN (250 3000) SIG_NAME M_D_CKE<3>
J 0
(260 3010);
DISPLAY 0.659574 (260 3010);
PAINT MONO (260 3010);
DISPLAY INVISIBLE (260 3010);
FORCEPROP 1 LASTPIN (250 3000) BN 3
J 0
(200 3010);
DISPLAY 0.617021 (200 3010);
PAINT PINK (200 3010);
FORCEPROP 2 LAST CDS_LIB mstr_standard
J 0
(200 3000);
DISPLAY 0.787234 (200 3000);
PAINT MONO (200 3000);
DISPLAY INVISIBLE (200 3000);
FORCEPROP 1 LAST BODY_TYPE PLUMBING
J 0
(200 2950);
DISPLAY 1.234043 (200 2950);
PAINT GREEN (200 2950);
DISPLAY INVISIBLE (200 2950);
FORCEPROP 1 LAST HDL_TAP TRUE
J 0
(525 2875);
DISPLAY 1.234043 (525 2875);
PAINT GREEN (525 2875);
DISPLAY INVISIBLE (525 2875);
FORCEPROP 1 LAST PATH I139
J 0
(198 3000);
DISPLAY 0.872340 (198 3000);
PAINT GREEN (198 3000);
DISPLAY INVISIBLE (198 3000);
FORCEADD TAP..6
R 2
(4100 4500);
FORCEPROP 3 LASTPIN (4050 4500) SIG_NAME M_D_DQS_DP<14>
J 0
(4060 4510);
DISPLAY 0.659574 (4060 4510);
PAINT MONO (4060 4510);
DISPLAY INVISIBLE (4060 4510);
FORCEPROP 1 LASTPIN (4050 4500) BN 14
J 2
(4100 4510);
DISPLAY 0.617021 (4100 4510);
PAINT PINK (4100 4510);
FORCEPROP 2 LAST CDS_LIB mstr_standard
J 0
(4100 4500);
DISPLAY 0.787234 (4100 4500);
PAINT MONO (4100 4500);
DISPLAY INVISIBLE (4100 4500);
FORCEPROP 1 LAST BODY_TYPE PLUMBING
J 2
(4100 4450);
DISPLAY 1.234043 (4100 4450);
PAINT GREEN (4100 4450);
DISPLAY INVISIBLE (4100 4450);
FORCEPROP 1 LAST HDL_TAP TRUE
J 2
(3775 4375);
DISPLAY 1.234043 (3775 4375);
PAINT GREEN (3775 4375);
DISPLAY INVISIBLE (3775 4375);
FORCEPROP 1 LAST PATH I14
J 2
(4102 4500);
DISPLAY 0.872340 (4102 4500);
PAINT GREEN (4102 4500);
DISPLAY INVISIBLE (4102 4500);
FORCEADD TAP..6
(200 2850);
FORCEPROP 3 LASTPIN (250 2850) SIG_NAME M_D_ODT<3>
J 0
(260 2860);
DISPLAY 0.659574 (260 2860);
PAINT MONO (260 2860);
DISPLAY INVISIBLE (260 2860);
FORCEPROP 1 LASTPIN (250 2850) BN 3
J 0
(200 2860);
DISPLAY 0.617021 (200 2860);
PAINT PINK (200 2860);
FORCEPROP 2 LAST CDS_LIB mstr_standard
J 0
(200 2850);
DISPLAY 0.787234 (200 2850);
PAINT MONO (200 2850);
DISPLAY INVISIBLE (200 2850);
FORCEPROP 1 LAST BODY_TYPE PLUMBING
J 0
(200 2800);
DISPLAY 1.234043 (200 2800);
PAINT GREEN (200 2800);
DISPLAY INVISIBLE (200 2800);
FORCEPROP 1 LAST HDL_TAP TRUE
J 0
(525 2725);
DISPLAY 1.234043 (525 2725);
PAINT GREEN (525 2725);
DISPLAY INVISIBLE (525 2725);
FORCEPROP 1 LAST PATH I140
J 0
(198 2850);
DISPLAY 0.872340 (198 2850);
PAINT GREEN (198 2850);
DISPLAY INVISIBLE (198 2850);
FORCEADD TAP..6
(200 2650);
FORCEPROP 3 LASTPIN (250 2650) SIG_NAME M_D_ECC<6>
J 0
(260 2660);
DISPLAY 0.659574 (260 2660);
PAINT MONO (260 2660);
DISPLAY INVISIBLE (260 2660);
FORCEPROP 1 LASTPIN (250 2650) BN 6
J 0
(200 2660);
DISPLAY 0.617021 (200 2660);
PAINT PINK (200 2660);
FORCEPROP 2 LAST CDS_LIB mstr_standard
J 0
(200 2650);
DISPLAY 0.787234 (200 2650);
PAINT MONO (200 2650);
DISPLAY INVISIBLE (200 2650);
FORCEPROP 1 LAST BODY_TYPE PLUMBING
J 0
(200 2600);
DISPLAY 1.234043 (200 2600);
PAINT GREEN (200 2600);
DISPLAY INVISIBLE (200 2600);
FORCEPROP 1 LAST HDL_TAP TRUE
J 0
(525 2525);
DISPLAY 1.234043 (525 2525);
PAINT GREEN (525 2525);
DISPLAY INVISIBLE (525 2525);
FORCEPROP 1 LAST PATH I141
J 0
(198 2650);
DISPLAY 0.872340 (198 2650);
PAINT GREEN (198 2650);
DISPLAY INVISIBLE (198 2650);
FORCEADD TAP..6
(200 2700);
FORCEPROP 3 LASTPIN (250 2700) SIG_NAME M_D_ECC<7>
J 0
(260 2710);
DISPLAY 0.659574 (260 2710);
PAINT MONO (260 2710);
DISPLAY INVISIBLE (260 2710);
FORCEPROP 1 LASTPIN (250 2700) BN 7
J 0
(200 2710);
DISPLAY 0.617021 (200 2710);
PAINT PINK (200 2710);
FORCEPROP 2 LAST CDS_LIB mstr_standard
J 0
(200 2700);
DISPLAY 0.787234 (200 2700);
PAINT MONO (200 2700);
DISPLAY INVISIBLE (200 2700);
FORCEPROP 1 LAST BODY_TYPE PLUMBING
J 0
(200 2650);
DISPLAY 1.234043 (200 2650);
PAINT GREEN (200 2650);
DISPLAY INVISIBLE (200 2650);
FORCEPROP 1 LAST HDL_TAP TRUE
J 0
(525 2575);
DISPLAY 1.234043 (525 2575);
PAINT GREEN (525 2575);
DISPLAY INVISIBLE (525 2575);
FORCEPROP 1 LAST PATH I142
J 0
(198 2700);
DISPLAY 0.872340 (198 2700);
PAINT GREEN (198 2700);
DISPLAY INVISIBLE (198 2700);
FORCEADD TAP..6
(200 2600);
FORCEPROP 3 LASTPIN (250 2600) SIG_NAME M_D_ECC<5>
J 0
(260 2610);
DISPLAY 0.659574 (260 2610);
PAINT MONO (260 2610);
DISPLAY INVISIBLE (260 2610);
FORCEPROP 1 LASTPIN (250 2600) BN 5
J 0
(200 2610);
DISPLAY 0.617021 (200 2610);
PAINT PINK (200 2610);
FORCEPROP 2 LAST CDS_LIB mstr_standard
J 0
(200 2600);
DISPLAY 0.787234 (200 2600);
PAINT MONO (200 2600);
DISPLAY INVISIBLE (200 2600);
FORCEPROP 1 LAST BODY_TYPE PLUMBING
J 0
(200 2550);
DISPLAY 1.234043 (200 2550);
PAINT GREEN (200 2550);
DISPLAY INVISIBLE (200 2550);
FORCEPROP 1 LAST HDL_TAP TRUE
J 0
(525 2475);
DISPLAY 1.234043 (525 2475);
PAINT GREEN (525 2475);
DISPLAY INVISIBLE (525 2475);
FORCEPROP 1 LAST PATH I143
J 0
(198 2600);
DISPLAY 0.872340 (198 2600);
PAINT GREEN (198 2600);
DISPLAY INVISIBLE (198 2600);
FORCEADD TAP..6
(200 2550);
FORCEPROP 3 LASTPIN (250 2550) SIG_NAME M_D_ECC<4>
J 0
(260 2560);
DISPLAY 0.659574 (260 2560);
PAINT MONO (260 2560);
DISPLAY INVISIBLE (260 2560);
FORCEPROP 1 LASTPIN (250 2550) BN 4
J 0
(200 2560);
DISPLAY 0.617021 (200 2560);
PAINT PINK (200 2560);
FORCEPROP 2 LAST CDS_LIB mstr_standard
J 0
(200 2550);
DISPLAY 0.787234 (200 2550);
PAINT MONO (200 2550);
DISPLAY INVISIBLE (200 2550);
FORCEPROP 1 LAST BODY_TYPE PLUMBING
J 0
(200 2500);
DISPLAY 1.234043 (200 2500);
PAINT GREEN (200 2500);
DISPLAY INVISIBLE (200 2500);
FORCEPROP 1 LAST HDL_TAP TRUE
J 0
(525 2425);
DISPLAY 1.234043 (525 2425);
PAINT GREEN (525 2425);
DISPLAY INVISIBLE (525 2425);
FORCEPROP 1 LAST PATH I144
J 0
(198 2550);
DISPLAY 0.872340 (198 2550);
PAINT GREEN (198 2550);
DISPLAY INVISIBLE (198 2550);
FORCEADD TAP..6
(200 2350);
FORCEPROP 3 LASTPIN (250 2350) SIG_NAME M_D_ECC<0>
J 0
(260 2360);
DISPLAY 0.659574 (260 2360);
PAINT MONO (260 2360);
DISPLAY INVISIBLE (260 2360);
FORCEPROP 1 LASTPIN (250 2350) BN 0
J 0
(200 2360);
DISPLAY 0.617021 (200 2360);
PAINT PINK (200 2360);
FORCEPROP 2 LAST CDS_LIB mstr_standard
J 0
(200 2350);
DISPLAY 0.787234 (200 2350);
PAINT MONO (200 2350);
DISPLAY INVISIBLE (200 2350);
FORCEPROP 1 LAST BODY_TYPE PLUMBING
J 0
(200 2300);
DISPLAY 1.234043 (200 2300);
PAINT GREEN (200 2300);
DISPLAY INVISIBLE (200 2300);
FORCEPROP 1 LAST HDL_TAP TRUE
J 0
(525 2225);
DISPLAY 1.234043 (525 2225);
PAINT GREEN (525 2225);
DISPLAY INVISIBLE (525 2225);
FORCEPROP 1 LAST PATH I145
J 0
(198 2350);
DISPLAY 0.872340 (198 2350);
PAINT GREEN (198 2350);
DISPLAY INVISIBLE (198 2350);
FORCEADD TAP..6
(200 2400);
FORCEPROP 3 LASTPIN (250 2400) SIG_NAME M_D_ECC<1>
J 0
(260 2410);
DISPLAY 0.659574 (260 2410);
PAINT MONO (260 2410);
DISPLAY INVISIBLE (260 2410);
FORCEPROP 1 LASTPIN (250 2400) BN 1
J 0
(200 2410);
DISPLAY 0.617021 (200 2410);
PAINT PINK (200 2410);
FORCEPROP 2 LAST CDS_LIB mstr_standard
J 0
(200 2400);
DISPLAY 0.787234 (200 2400);
PAINT MONO (200 2400);
DISPLAY INVISIBLE (200 2400);
FORCEPROP 1 LAST BODY_TYPE PLUMBING
J 0
(200 2350);
DISPLAY 1.234043 (200 2350);
PAINT GREEN (200 2350);
DISPLAY INVISIBLE (200 2350);
FORCEPROP 1 LAST HDL_TAP TRUE
J 0
(525 2275);
DISPLAY 1.234043 (525 2275);
PAINT GREEN (525 2275);
DISPLAY INVISIBLE (525 2275);
FORCEPROP 1 LAST PATH I146
J 0
(198 2400);
DISPLAY 0.872340 (198 2400);
PAINT GREEN (198 2400);
DISPLAY INVISIBLE (198 2400);
FORCEADD TAP..6
(200 2450);
FORCEPROP 3 LASTPIN (250 2450) SIG_NAME M_D_ECC<2>
J 0
(260 2460);
DISPLAY 0.659574 (260 2460);
PAINT MONO (260 2460);
DISPLAY INVISIBLE (260 2460);
FORCEPROP 1 LASTPIN (250 2450) BN 2
J 0
(200 2460);
DISPLAY 0.617021 (200 2460);
PAINT PINK (200 2460);
FORCEPROP 2 LAST CDS_LIB mstr_standard
J 0
(200 2450);
DISPLAY 0.787234 (200 2450);
PAINT MONO (200 2450);
DISPLAY INVISIBLE (200 2450);
FORCEPROP 1 LAST BODY_TYPE PLUMBING
J 0
(200 2400);
DISPLAY 1.234043 (200 2400);
PAINT GREEN (200 2400);
DISPLAY INVISIBLE (200 2400);
FORCEPROP 1 LAST HDL_TAP TRUE
J 0
(525 2325);
DISPLAY 1.234043 (525 2325);
PAINT GREEN (525 2325);
DISPLAY INVISIBLE (525 2325);
FORCEPROP 1 LAST PATH I147
J 0
(198 2450);
DISPLAY 0.872340 (198 2450);
PAINT GREEN (198 2450);
DISPLAY INVISIBLE (198 2450);
FORCEADD TAP..6
(200 2500);
FORCEPROP 3 LASTPIN (250 2500) SIG_NAME M_D_ECC<3>
J 0
(260 2510);
DISPLAY 0.659574 (260 2510);
PAINT MONO (260 2510);
DISPLAY INVISIBLE (260 2510);
FORCEPROP 1 LASTPIN (250 2500) BN 3
J 0
(200 2510);
DISPLAY 0.617021 (200 2510);
PAINT PINK (200 2510);
FORCEPROP 2 LAST CDS_LIB mstr_standard
J 0
(200 2500);
DISPLAY 0.787234 (200 2500);
PAINT MONO (200 2500);
DISPLAY INVISIBLE (200 2500);
FORCEPROP 1 LAST BODY_TYPE PLUMBING
J 0
(200 2450);
DISPLAY 1.234043 (200 2450);
PAINT GREEN (200 2450);
DISPLAY INVISIBLE (200 2450);
FORCEPROP 1 LAST HDL_TAP TRUE
J 0
(525 2375);
DISPLAY 1.234043 (525 2375);
PAINT GREEN (525 2375);
DISPLAY INVISIBLE (525 2375);
FORCEPROP 1 LAST PATH I148
J 0
(198 2500);
DISPLAY 0.872340 (198 2500);
PAINT GREEN (198 2500);
DISPLAY INVISIBLE (198 2500);
FORCEADD TAP..6
R 2
(1700 1850);
FORCEPROP 3 LASTPIN (1650 1850) SIG_NAME M_D_DQ<5>
J 0
(1660 1860);
DISPLAY 0.659574 (1660 1860);
PAINT MONO (1660 1860);
DISPLAY INVISIBLE (1660 1860);
FORCEPROP 1 LASTPIN (1650 1850) BN 5
J 2
(1700 1860);
DISPLAY 0.617021 (1700 1860);
PAINT PINK (1700 1860);
FORCEPROP 2 LAST CDS_LIB mstr_standard
J 2
(1700 1850);
DISPLAY 0.787234 (1700 1850);
PAINT MONO (1700 1850);
DISPLAY INVISIBLE (1700 1850);
FORCEPROP 1 LAST BODY_TYPE PLUMBING
J 2
(1700 1800);
DISPLAY 1.234043 (1700 1800);
PAINT GREEN (1700 1800);
DISPLAY INVISIBLE (1700 1800);
FORCEPROP 1 LAST HDL_TAP TRUE
J 2
(1375 1725);
DISPLAY 1.234043 (1375 1725);
PAINT GREEN (1375 1725);
DISPLAY INVISIBLE (1375 1725);
FORCEPROP 1 LAST PATH I149
J 2
(1702 1850);
DISPLAY 0.872340 (1702 1850);
PAINT GREEN (1702 1850);
DISPLAY INVISIBLE (1702 1850);
FORCEADD TAP..6
R 2
(4100 4400);
FORCEPROP 3 LASTPIN (4050 4400) SIG_NAME M_D_DQS_DP<13>
J 0
(4060 4410);
DISPLAY 0.659574 (4060 4410);
PAINT MONO (4060 4410);
DISPLAY INVISIBLE (4060 4410);
FORCEPROP 1 LASTPIN (4050 4400) BN 13
J 2
(4100 4410);
DISPLAY 0.617021 (4100 4410);
PAINT PINK (4100 4410);
FORCEPROP 2 LAST CDS_LIB mstr_standard
J 0
(4100 4400);
DISPLAY 0.787234 (4100 4400);
PAINT MONO (4100 4400);
DISPLAY INVISIBLE (4100 4400);
FORCEPROP 1 LAST BODY_TYPE PLUMBING
J 2
(4100 4350);
DISPLAY 1.234043 (4100 4350);
PAINT GREEN (4100 4350);
DISPLAY INVISIBLE (4100 4350);
FORCEPROP 1 LAST HDL_TAP TRUE
J 2
(3775 4275);
DISPLAY 1.234043 (3775 4275);
PAINT GREEN (3775 4275);
DISPLAY INVISIBLE (3775 4275);
FORCEPROP 1 LAST PATH I15
J 2
(4102 4400);
DISPLAY 0.872340 (4102 4400);
PAINT GREEN (4102 4400);
DISPLAY INVISIBLE (4102 4400);
FORCEADD TAP..6
R 2
(1700 1800);
FORCEPROP 3 LASTPIN (1650 1800) SIG_NAME M_D_DQ<4>
J 0
(1660 1810);
DISPLAY 0.659574 (1660 1810);
PAINT MONO (1660 1810);
DISPLAY INVISIBLE (1660 1810);
FORCEPROP 1 LASTPIN (1650 1800) BN 4
J 2
(1700 1810);
DISPLAY 0.617021 (1700 1810);
PAINT PINK (1700 1810);
FORCEPROP 2 LAST CDS_LIB mstr_standard
J 2
(1700 1800);
DISPLAY 0.787234 (1700 1800);
PAINT MONO (1700 1800);
DISPLAY INVISIBLE (1700 1800);
FORCEPROP 1 LAST BODY_TYPE PLUMBING
J 2
(1700 1750);
DISPLAY 1.234043 (1700 1750);
PAINT GREEN (1700 1750);
DISPLAY INVISIBLE (1700 1750);
FORCEPROP 1 LAST HDL_TAP TRUE
J 2
(1375 1675);
DISPLAY 1.234043 (1375 1675);
PAINT GREEN (1375 1675);
DISPLAY INVISIBLE (1375 1675);
FORCEPROP 1 LAST PATH I150
J 2
(1702 1800);
DISPLAY 0.872340 (1702 1800);
PAINT GREEN (1702 1800);
DISPLAY INVISIBLE (1702 1800);
FORCEADD TAP..6
R 2
(1700 1950);
FORCEPROP 3 LASTPIN (1650 1950) SIG_NAME M_D_DQ<7>
J 0
(1660 1960);
DISPLAY 0.659574 (1660 1960);
PAINT MONO (1660 1960);
DISPLAY INVISIBLE (1660 1960);
FORCEPROP 1 LASTPIN (1650 1950) BN 7
J 2
(1700 1960);
DISPLAY 0.617021 (1700 1960);
PAINT PINK (1700 1960);
FORCEPROP 2 LAST CDS_LIB mstr_standard
J 2
(1700 1950);
DISPLAY 0.787234 (1700 1950);
PAINT MONO (1700 1950);
DISPLAY INVISIBLE (1700 1950);
FORCEPROP 1 LAST BODY_TYPE PLUMBING
J 2
(1700 1900);
DISPLAY 1.234043 (1700 1900);
PAINT GREEN (1700 1900);
DISPLAY INVISIBLE (1700 1900);
FORCEPROP 1 LAST HDL_TAP TRUE
J 2
(1375 1825);
DISPLAY 1.234043 (1375 1825);
PAINT GREEN (1375 1825);
DISPLAY INVISIBLE (1375 1825);
FORCEPROP 1 LAST PATH I151
J 2
(1702 1950);
DISPLAY 0.872340 (1702 1950);
PAINT GREEN (1702 1950);
DISPLAY INVISIBLE (1702 1950);
FORCEADD TAP..6
R 2
(1700 2000);
FORCEPROP 3 LASTPIN (1650 2000) SIG_NAME M_D_DQ<8>
J 0
(1660 2010);
DISPLAY 0.659574 (1660 2010);
PAINT MONO (1660 2010);
DISPLAY INVISIBLE (1660 2010);
FORCEPROP 1 LASTPIN (1650 2000) BN 8
J 2
(1700 2010);
DISPLAY 0.617021 (1700 2010);
PAINT PINK (1700 2010);
FORCEPROP 2 LAST CDS_LIB mstr_standard
J 2
(1700 2000);
DISPLAY 0.787234 (1700 2000);
PAINT MONO (1700 2000);
DISPLAY INVISIBLE (1700 2000);
FORCEPROP 1 LAST BODY_TYPE PLUMBING
J 2
(1700 1950);
DISPLAY 1.234043 (1700 1950);
PAINT GREEN (1700 1950);
DISPLAY INVISIBLE (1700 1950);
FORCEPROP 1 LAST HDL_TAP TRUE
J 2
(1375 1875);
DISPLAY 1.234043 (1375 1875);
PAINT GREEN (1375 1875);
DISPLAY INVISIBLE (1375 1875);
FORCEPROP 1 LAST PATH I152
J 2
(1702 2000);
DISPLAY 0.872340 (1702 2000);
PAINT GREEN (1702 2000);
DISPLAY INVISIBLE (1702 2000);
FORCEADD TAP..6
R 2
(1700 1900);
FORCEPROP 3 LASTPIN (1650 1900) SIG_NAME M_D_DQ<6>
J 0
(1660 1910);
DISPLAY 0.659574 (1660 1910);
PAINT MONO (1660 1910);
DISPLAY INVISIBLE (1660 1910);
FORCEPROP 1 LASTPIN (1650 1900) BN 6
J 2
(1700 1910);
DISPLAY 0.617021 (1700 1910);
PAINT PINK (1700 1910);
FORCEPROP 2 LAST CDS_LIB mstr_standard
J 2
(1700 1900);
DISPLAY 0.787234 (1700 1900);
PAINT MONO (1700 1900);
DISPLAY INVISIBLE (1700 1900);
FORCEPROP 1 LAST BODY_TYPE PLUMBING
J 2
(1700 1850);
DISPLAY 1.234043 (1700 1850);
PAINT GREEN (1700 1850);
DISPLAY INVISIBLE (1700 1850);
FORCEPROP 1 LAST HDL_TAP TRUE
J 2
(1375 1775);
DISPLAY 1.234043 (1375 1775);
PAINT GREEN (1375 1775);
DISPLAY INVISIBLE (1375 1775);
FORCEPROP 1 LAST PATH I153
J 2
(1702 1900);
DISPLAY 0.872340 (1702 1900);
PAINT GREEN (1702 1900);
DISPLAY INVISIBLE (1702 1900);
FORCEADD TAP..6
R 2
(1700 1600);
FORCEPROP 3 LASTPIN (1650 1600) SIG_NAME M_D_DQ<0>
J 0
(1660 1610);
DISPLAY 0.659574 (1660 1610);
PAINT MONO (1660 1610);
DISPLAY INVISIBLE (1660 1610);
FORCEPROP 1 LASTPIN (1650 1600) BN 0
J 2
(1700 1610);
DISPLAY 0.617021 (1700 1610);
PAINT PINK (1700 1610);
FORCEPROP 2 LAST CDS_LIB mstr_standard
J 2
(1700 1600);
DISPLAY 0.787234 (1700 1600);
PAINT MONO (1700 1600);
DISPLAY INVISIBLE (1700 1600);
FORCEPROP 1 LAST BODY_TYPE PLUMBING
J 2
(1700 1550);
DISPLAY 1.234043 (1700 1550);
PAINT GREEN (1700 1550);
DISPLAY INVISIBLE (1700 1550);
FORCEPROP 1 LAST HDL_TAP TRUE
J 2
(1375 1475);
DISPLAY 1.234043 (1375 1475);
PAINT GREEN (1375 1475);
DISPLAY INVISIBLE (1375 1475);
FORCEPROP 1 LAST PATH I154
J 2
(1702 1600);
DISPLAY 0.872340 (1702 1600);
PAINT GREEN (1702 1600);
DISPLAY INVISIBLE (1702 1600);
FORCEADD TAP..6
R 2
(1700 1700);
FORCEPROP 3 LASTPIN (1650 1700) SIG_NAME M_D_DQ<2>
J 0
(1660 1710);
DISPLAY 0.659574 (1660 1710);
PAINT MONO (1660 1710);
DISPLAY INVISIBLE (1660 1710);
FORCEPROP 1 LASTPIN (1650 1700) BN 2
J 2
(1700 1710);
DISPLAY 0.617021 (1700 1710);
PAINT PINK (1700 1710);
FORCEPROP 2 LAST CDS_LIB mstr_standard
J 2
(1700 1700);
DISPLAY 0.787234 (1700 1700);
PAINT MONO (1700 1700);
DISPLAY INVISIBLE (1700 1700);
FORCEPROP 1 LAST BODY_TYPE PLUMBING
J 2
(1700 1650);
DISPLAY 1.234043 (1700 1650);
PAINT GREEN (1700 1650);
DISPLAY INVISIBLE (1700 1650);
FORCEPROP 1 LAST HDL_TAP TRUE
J 2
(1375 1575);
DISPLAY 1.234043 (1375 1575);
PAINT GREEN (1375 1575);
DISPLAY INVISIBLE (1375 1575);
FORCEPROP 1 LAST PATH I155
J 2
(1702 1700);
DISPLAY 0.872340 (1702 1700);
PAINT GREEN (1702 1700);
DISPLAY INVISIBLE (1702 1700);
FORCEADD TAP..6
R 2
(1700 1650);
FORCEPROP 3 LASTPIN (1650 1650) SIG_NAME M_D_DQ<1>
J 0
(1660 1660);
DISPLAY 0.659574 (1660 1660);
PAINT MONO (1660 1660);
DISPLAY INVISIBLE (1660 1660);
FORCEPROP 1 LASTPIN (1650 1650) BN 1
J 2
(1700 1660);
DISPLAY 0.617021 (1700 1660);
PAINT PINK (1700 1660);
FORCEPROP 2 LAST CDS_LIB mstr_standard
J 2
(1700 1650);
DISPLAY 0.787234 (1700 1650);
PAINT MONO (1700 1650);
DISPLAY INVISIBLE (1700 1650);
FORCEPROP 1 LAST BODY_TYPE PLUMBING
J 2
(1700 1600);
DISPLAY 1.234043 (1700 1600);
PAINT GREEN (1700 1600);
DISPLAY INVISIBLE (1700 1600);
FORCEPROP 1 LAST HDL_TAP TRUE
J 2
(1375 1525);
DISPLAY 1.234043 (1375 1525);
PAINT GREEN (1375 1525);
DISPLAY INVISIBLE (1375 1525);
FORCEPROP 1 LAST PATH I156
J 2
(1702 1650);
DISPLAY 0.872340 (1702 1650);
PAINT GREEN (1702 1650);
DISPLAY INVISIBLE (1702 1650);
FORCEADD TAP..6
R 2
(1700 1750);
FORCEPROP 3 LASTPIN (1650 1750) SIG_NAME M_D_DQ<3>
J 0
(1660 1760);
DISPLAY 0.659574 (1660 1760);
PAINT MONO (1660 1760);
DISPLAY INVISIBLE (1660 1760);
FORCEPROP 1 LASTPIN (1650 1750) BN 3
J 2
(1700 1760);
DISPLAY 0.617021 (1700 1760);
PAINT PINK (1700 1760);
FORCEPROP 2 LAST CDS_LIB mstr_standard
J 2
(1700 1750);
DISPLAY 0.787234 (1700 1750);
PAINT MONO (1700 1750);
DISPLAY INVISIBLE (1700 1750);
FORCEPROP 1 LAST BODY_TYPE PLUMBING
J 2
(1700 1700);
DISPLAY 1.234043 (1700 1700);
PAINT GREEN (1700 1700);
DISPLAY INVISIBLE (1700 1700);
FORCEPROP 1 LAST HDL_TAP TRUE
J 2
(1375 1625);
DISPLAY 1.234043 (1375 1625);
PAINT GREEN (1375 1625);
DISPLAY INVISIBLE (1375 1625);
FORCEPROP 1 LAST PATH I157
J 2
(1702 1750);
DISPLAY 0.872340 (1702 1750);
PAINT GREEN (1702 1750);
DISPLAY INVISIBLE (1702 1750);
FORCEADD SCONN288_H44441003..1
(950 3100);
FORCEPROP 2 LASTPIN (450 1600) $PN 146
J 2
(440 1610);
DISPLAY 0.617021 (440 1610);
PAINT ORANGE (440 1610);
FORCEPROP 2 LASTPIN (450 1950) $PN 284
J 2
(440 1960);
DISPLAY 0.617021 (440 1960);
PAINT ORANGE (440 1960);
FORCEPROP 2 LASTPIN (450 1750) $PN 285
J 2
(440 1760);
DISPLAY 0.617021 (440 1760);
PAINT ORANGE (440 1760);
FORCEPROP 2 LASTPIN (450 1700) $PN 141
J 2
(440 1710);
DISPLAY 0.617021 (440 1710);
PAINT ORANGE (440 1710);
FORCEPROP 2 LASTPIN (450 1300) $PN 230
J 2
(440 1310);
DISPLAY 0.617021 (440 1310);
PAINT ORANGE (440 1310);
FORCEPROP 2 LASTPIN (450 1900) $PN 238
J 2
(440 1910);
DISPLAY 0.617021 (440 1910);
PAINT ORANGE (440 1910);
FORCEPROP 2 LASTPIN (450 1850) $PN 140
J 2
(440 1860);
DISPLAY 0.617021 (440 1860);
PAINT ORANGE (440 1860);
FORCEPROP 2 LASTPIN (450 1800) $PN 139
J 2
(440 1810);
DISPLAY 0.617021 (440 1810);
PAINT ORANGE (440 1810);
FORCEPROP 2 LASTPIN (450 3250) $PN 237
J 2
(440 3260);
DISPLAY 0.617021 (440 3260);
PAINT ORANGE (440 3260);
FORCEPROP 2 LASTPIN (450 3200) $PN 93
J 2
(440 3210);
DISPLAY 0.617021 (440 3210);
PAINT ORANGE (440 3210);
FORCEPROP 2 LASTPIN (450 3150) $PN 89
J 2
(440 3160);
DISPLAY 0.617021 (440 3160);
PAINT ORANGE (440 3160);
FORCEPROP 2 LASTPIN (450 3100) $PN 84
J 2
(440 3110);
DISPLAY 0.617021 (440 3110);
PAINT ORANGE (440 3110);
FORCEPROP 2 LASTPIN (450 1500) $PN 144
J 2
(440 1510);
DISPLAY 0.617021 (440 1510);
PAINT ORANGE (440 1510);
FORCEPROP 2 LASTPIN (450 1450) $PN 227
J 2
(440 1460);
DISPLAY 0.617021 (440 1460);
PAINT ORANGE (440 1460);
FORCEPROP 2 LASTPIN (450 1400) $PN 205
J 2
(440 1410);
DISPLAY 0.617021 (440 1410);
PAINT ORANGE (440 1410);
FORCEPROP 2 LASTPIN (450 2200) $PN 58
J 2
(440 2210);
DISPLAY 0.617021 (440 2210);
PAINT ORANGE (440 2210);
FORCEPROP 2 LASTPIN (450 2250) $PN 222
J 2
(440 2260);
DISPLAY 0.617021 (440 2260);
PAINT ORANGE (440 2260);
FORCEPROP 2 LASTPIN (450 2850) $PN 91
J 2
(440 2860);
DISPLAY 0.617021 (440 2860);
PAINT ORANGE (440 2860);
FORCEPROP 2 LASTPIN (450 2800) $PN 87
J 2
(440 2810);
DISPLAY 0.617021 (440 2810);
PAINT ORANGE (440 2810);
FORCEPROP 2 LASTPIN (450 2150) $PN 78
J 2
(440 2160);
DISPLAY 0.617021 (440 2160);
PAINT ORANGE (440 2160);
FORCEPROP 2 LASTPIN (1450 4750) $PN 280
J 0
(1460 4760);
DISPLAY 0.617021 (1460 4760);
PAINT ORANGE (1460 4760);
FORCEPROP 2 LASTPIN (1450 4700) $PN 135
J 0
(1460 4710);
DISPLAY 0.617021 (1460 4710);
PAINT ORANGE (1460 4710);
FORCEPROP 2 LASTPIN (1450 4650) $PN 273
J 0
(1460 4660);
DISPLAY 0.617021 (1460 4660);
PAINT ORANGE (1460 4660);
FORCEPROP 2 LASTPIN (1450 4450) $PN 275
J 0
(1460 4460);
DISPLAY 0.617021 (1460 4460);
PAINT ORANGE (1460 4460);
FORCEPROP 2 LASTPIN (1450 4400) $PN 130
J 0
(1460 4410);
DISPLAY 0.617021 (1460 4410);
PAINT ORANGE (1460 4410);
FORCEPROP 2 LASTPIN (1450 4350) $PN 269
J 0
(1460 4360);
DISPLAY 0.617021 (1460 4360);
PAINT ORANGE (1460 4360);
FORCEPROP 2 LASTPIN (1450 4250) $PN 262
J 0
(1460 4260);
DISPLAY 0.617021 (1460 4260);
PAINT ORANGE (1460 4260);
FORCEPROP 2 LASTPIN (1450 4050) $PN 264
J 0
(1460 4060);
DISPLAY 0.617021 (1460 4060);
PAINT ORANGE (1460 4060);
FORCEPROP 2 LASTPIN (1450 4000) $PN 119
J 0
(1460 4010);
DISPLAY 0.617021 (1460 4010);
PAINT ORANGE (1460 4010);
FORCEPROP 2 LASTPIN (1450 3950) $PN 258
J 0
(1460 3960);
DISPLAY 0.617021 (1460 3960);
PAINT ORANGE (1460 3960);
FORCEPROP 2 LASTPIN (1450 3900) $PN 113
J 0
(1460 3910);
DISPLAY 0.617021 (1460 3910);
PAINT ORANGE (1460 3910);
FORCEPROP 2 LASTPIN (1450 3850) $PN 251
J 0
(1460 3860);
DISPLAY 0.617021 (1460 3860);
PAINT ORANGE (1460 3860);
FORCEPROP 2 LASTPIN (1450 3800) $PN 106
J 0
(1460 3810);
DISPLAY 0.617021 (1460 3810);
PAINT ORANGE (1460 3810);
FORCEPROP 2 LASTPIN (1450 3750) $PN 260
J 0
(1460 3760);
DISPLAY 0.617021 (1460 3760);
PAINT ORANGE (1460 3760);
FORCEPROP 2 LASTPIN (1450 3700) $PN 115
J 0
(1460 3710);
DISPLAY 0.617021 (1460 3710);
PAINT ORANGE (1460 3710);
FORCEPROP 2 LASTPIN (1450 3650) $PN 253
J 0
(1460 3660);
DISPLAY 0.617021 (1460 3660);
PAINT ORANGE (1460 3660);
FORCEPROP 2 LASTPIN (1450 3600) $PN 108
J 0
(1460 3610);
DISPLAY 0.617021 (1460 3610);
PAINT ORANGE (1460 3610);
FORCEPROP 2 LASTPIN (1450 3550) $PN 247
J 0
(1460 3560);
DISPLAY 0.617021 (1460 3560);
PAINT ORANGE (1460 3560);
FORCEPROP 2 LASTPIN (1450 3450) $PN 240
J 0
(1460 3460);
DISPLAY 0.617021 (1460 3460);
PAINT ORANGE (1460 3460);
FORCEPROP 2 LASTPIN (1450 3400) $PN 95
J 0
(1460 3410);
DISPLAY 0.617021 (1460 3410);
PAINT ORANGE (1460 3410);
FORCEPROP 2 LASTPIN (1450 3350) $PN 249
J 0
(1460 3360);
DISPLAY 0.617021 (1460 3360);
PAINT ORANGE (1460 3360);
FORCEPROP 2 LASTPIN (1450 3300) $PN 104
J 0
(1460 3310);
DISPLAY 0.617021 (1460 3310);
PAINT ORANGE (1460 3310);
FORCEPROP 2 LASTPIN (1450 3250) $PN 242
J 0
(1460 3260);
DISPLAY 0.617021 (1460 3260);
PAINT ORANGE (1460 3260);
FORCEPROP 2 LASTPIN (1450 3200) $PN 97
J 0
(1460 3210);
DISPLAY 0.617021 (1460 3210);
PAINT ORANGE (1460 3210);
FORCEPROP 2 LASTPIN (1450 3150) $PN 188
J 0
(1460 3160);
DISPLAY 0.617021 (1460 3160);
PAINT ORANGE (1460 3160);
FORCEPROP 2 LASTPIN (1450 3100) $PN 43
J 0
(1460 3110);
DISPLAY 0.617021 (1460 3110);
PAINT ORANGE (1460 3110);
FORCEPROP 2 LASTPIN (1450 3050) $PN 181
J 0
(1460 3060);
DISPLAY 0.617021 (1460 3060);
PAINT ORANGE (1460 3060);
FORCEPROP 2 LASTPIN (1450 3000) $PN 36
J 0
(1460 3010);
DISPLAY 0.617021 (1460 3010);
PAINT ORANGE (1460 3010);
FORCEPROP 2 LASTPIN (1450 2950) $PN 190
J 0
(1460 2960);
DISPLAY 0.617021 (1460 2960);
PAINT ORANGE (1460 2960);
FORCEPROP 2 LASTPIN (1450 2900) $PN 45
J 0
(1460 2910);
DISPLAY 0.617021 (1460 2910);
PAINT ORANGE (1460 2910);
FORCEPROP 2 LASTPIN (1450 2850) $PN 183
J 0
(1460 2860);
DISPLAY 0.617021 (1460 2860);
PAINT ORANGE (1460 2860);
FORCEPROP 2 LASTPIN (1450 2800) $PN 38
J 0
(1460 2810);
DISPLAY 0.617021 (1460 2810);
PAINT ORANGE (1460 2810);
FORCEPROP 2 LASTPIN (1450 2750) $PN 177
J 0
(1460 2760);
DISPLAY 0.617021 (1460 2760);
PAINT ORANGE (1460 2760);
FORCEPROP 2 LASTPIN (1450 2700) $PN 32
J 0
(1460 2710);
DISPLAY 0.617021 (1460 2710);
PAINT ORANGE (1460 2710);
FORCEPROP 2 LASTPIN (1450 2650) $PN 170
J 0
(1460 2660);
DISPLAY 0.617021 (1460 2660);
PAINT ORANGE (1460 2660);
FORCEPROP 2 LASTPIN (1450 2600) $PN 25
J 0
(1460 2610);
DISPLAY 0.617021 (1460 2610);
PAINT ORANGE (1460 2610);
FORCEPROP 2 LASTPIN (1450 2550) $PN 179
J 0
(1460 2560);
DISPLAY 0.617021 (1460 2560);
PAINT ORANGE (1460 2560);
FORCEPROP 2 LASTPIN (1450 2500) $PN 34
J 0
(1460 2510);
DISPLAY 0.617021 (1460 2510);
PAINT ORANGE (1460 2510);
FORCEPROP 2 LASTPIN (1450 2350) $PN 166
J 0
(1460 2360);
DISPLAY 0.617021 (1460 2360);
PAINT ORANGE (1460 2360);
FORCEPROP 2 LASTPIN (1450 2300) $PN 21
J 0
(1460 2310);
DISPLAY 0.617021 (1460 2310);
PAINT ORANGE (1460 2310);
FORCEPROP 2 LASTPIN (1450 2250) $PN 159
J 0
(1460 2260);
DISPLAY 0.617021 (1460 2260);
PAINT ORANGE (1460 2260);
FORCEPROP 2 LASTPIN (1450 2200) $PN 14
J 0
(1460 2210);
DISPLAY 0.617021 (1460 2210);
PAINT ORANGE (1460 2210);
FORCEPROP 2 LASTPIN (1450 2150) $PN 168
J 0
(1460 2160);
DISPLAY 0.617021 (1460 2160);
PAINT ORANGE (1460 2160);
FORCEPROP 2 LASTPIN (1450 2100) $PN 23
J 0
(1460 2110);
DISPLAY 0.617021 (1460 2110);
PAINT ORANGE (1460 2110);
FORCEPROP 2 LASTPIN (1450 2050) $PN 161
J 0
(1460 2060);
DISPLAY 0.617021 (1460 2060);
PAINT ORANGE (1460 2060);
FORCEPROP 2 LASTPIN (1450 2000) $PN 16
J 0
(1460 2010);
DISPLAY 0.617021 (1460 2010);
PAINT ORANGE (1460 2010);
FORCEPROP 2 LASTPIN (1450 1950) $PN 155
J 0
(1460 1960);
DISPLAY 0.617021 (1460 1960);
PAINT ORANGE (1460 1960);
FORCEPROP 2 LASTPIN (1450 1900) $PN 10
J 0
(1460 1910);
DISPLAY 0.617021 (1460 1910);
PAINT ORANGE (1460 1910);
FORCEPROP 2 LASTPIN (1450 1850) $PN 148
J 0
(1460 1860);
DISPLAY 0.617021 (1460 1860);
PAINT ORANGE (1460 1860);
FORCEPROP 2 LASTPIN (1450 1800) $PN 3
J 0
(1460 1810);
DISPLAY 0.617021 (1460 1810);
PAINT ORANGE (1460 1810);
FORCEPROP 2 LASTPIN (1450 1750) $PN 157
J 0
(1460 1760);
DISPLAY 0.617021 (1460 1760);
PAINT ORANGE (1460 1760);
FORCEPROP 2 LASTPIN (1450 1700) $PN 12
J 0
(1460 1710);
DISPLAY 0.617021 (1460 1710);
PAINT ORANGE (1460 1710);
FORCEPROP 2 LASTPIN (1450 1650) $PN 150
J 0
(1460 1660);
DISPLAY 0.617021 (1460 1660);
PAINT ORANGE (1460 1660);
FORCEPROP 2 LASTPIN (1450 1600) $PN 5
J 0
(1460 1610);
DISPLAY 0.617021 (1460 1610);
PAINT ORANGE (1460 1610);
FORCEPROP 2 LASTPIN (450 3000) $PN 203
J 2
(440 3010);
DISPLAY 0.617021 (440 3010);
PAINT ORANGE (440 3010);
FORCEPROP 2 LASTPIN (450 2950) $PN 60
J 2
(440 2960);
DISPLAY 0.617021 (440 2960);
PAINT ORANGE (440 2960);
FORCEPROP 2 LASTPIN (450 3550) $PN 218
J 2
(440 3560);
DISPLAY 0.617021 (440 3560);
PAINT ORANGE (440 3560);
FORCEPROP 2 LASTPIN (450 3500) $PN 219
J 2
(440 3510);
DISPLAY 0.617021 (440 3510);
PAINT ORANGE (440 3510);
FORCEPROP 2 LASTPIN (450 3450) $PN 74
J 2
(440 3460);
DISPLAY 0.617021 (440 3460);
PAINT ORANGE (440 3460);
FORCEPROP 2 LASTPIN (450 3400) $PN 75
J 2
(440 3410);
DISPLAY 0.617021 (440 3410);
PAINT ORANGE (440 3410);
FORCEPROP 2 LASTPIN (450 2700) $PN 199
J 2
(440 2710);
DISPLAY 0.617021 (440 2710);
PAINT ORANGE (440 2710);
FORCEPROP 2 LASTPIN (450 2650) $PN 54
J 2
(440 2660);
DISPLAY 0.617021 (440 2660);
PAINT ORANGE (440 2660);
FORCEPROP 2 LASTPIN (450 2600) $PN 192
J 2
(440 2610);
DISPLAY 0.617021 (440 2610);
PAINT ORANGE (440 2610);
FORCEPROP 2 LASTPIN (450 2550) $PN 47
J 2
(440 2560);
DISPLAY 0.617021 (440 2560);
PAINT ORANGE (440 2560);
FORCEPROP 2 LASTPIN (450 2500) $PN 201
J 2
(440 2510);
DISPLAY 0.617021 (440 2510);
PAINT ORANGE (440 2510);
FORCEPROP 2 LASTPIN (450 2450) $PN 56
J 2
(440 2460);
DISPLAY 0.617021 (440 2460);
PAINT ORANGE (440 2460);
FORCEPROP 2 LASTPIN (450 2400) $PN 194
J 2
(440 2410);
DISPLAY 0.617021 (440 2410);
PAINT ORANGE (440 2410);
FORCEPROP 2 LASTPIN (450 2350) $PN 49
J 2
(440 2360);
DISPLAY 0.617021 (440 2360);
PAINT ORANGE (440 2360);
FORCEPROP 2 LASTPIN (450 3300) $PN 235
J 2
(440 3310);
DISPLAY 0.617021 (440 3310);
PAINT ORANGE (440 3310);
FORCEPROP 2 LASTPIN (450 3700) $PN 207
J 2
(440 3710);
DISPLAY 0.617021 (440 3710);
PAINT ORANGE (440 3710);
FORCEPROP 2 LASTPIN (450 3650) $PN 63
J 2
(440 3660);
DISPLAY 0.617021 (440 3660);
PAINT ORANGE (440 3660);
FORCEPROP 2 LASTPIN (450 3800) $PN 224
J 2
(440 3810);
DISPLAY 0.617021 (440 3810);
PAINT ORANGE (440 3810);
FORCEPROP 2 LASTPIN (450 3750) $PN 81
J 2
(440 3760);
DISPLAY 0.617021 (440 3760);
PAINT ORANGE (440 3760);
FORCEPROP 2 LASTPIN (450 2100) $PN 208
J 2
(440 2110);
DISPLAY 0.617021 (440 2110);
PAINT ORANGE (440 2110);
FORCEPROP 2 LASTPIN (450 2050) $PN 62
J 2
(440 2060);
DISPLAY 0.617021 (440 2060);
PAINT ORANGE (440 2060);
FORCEPROP 2 LASTPIN (450 4750) $PN 234
J 2
(440 4760);
DISPLAY 0.617021 (440 4760);
PAINT ORANGE (440 4760);
FORCEPROP 2 LASTPIN (450 4700) $PN 82
J 2
(440 4710);
DISPLAY 0.617021 (440 4710);
PAINT ORANGE (440 4710);
FORCEPROP 2 LASTPIN (450 4600) $PN 228
J 2
(440 4610);
DISPLAY 0.617021 (440 4610);
PAINT ORANGE (440 4610);
FORCEPROP 2 LASTPIN (450 4550) $PN 232
J 2
(440 4560);
DISPLAY 0.617021 (440 4560);
PAINT ORANGE (440 4560);
FORCEPROP 2 LASTPIN (450 4500) $PN 65
J 2
(440 4510);
DISPLAY 0.617021 (440 4510);
PAINT ORANGE (440 4510);
FORCEPROP 2 LASTPIN (450 4450) $PN 210
J 2
(440 4460);
DISPLAY 0.617021 (440 4460);
PAINT ORANGE (440 4460);
FORCEPROP 2 LASTPIN (450 4400) $PN 225
J 2
(440 4410);
DISPLAY 0.617021 (440 4410);
PAINT ORANGE (440 4410);
FORCEPROP 2 LASTPIN (450 4350) $PN 66
J 2
(440 4360);
DISPLAY 0.617021 (440 4360);
PAINT ORANGE (440 4360);
FORCEPROP 2 LASTPIN (450 4300) $PN 68
J 2
(440 4310);
DISPLAY 0.617021 (440 4310);
PAINT ORANGE (440 4310);
FORCEPROP 2 LASTPIN (450 4250) $PN 211
J 2
(440 4260);
DISPLAY 0.617021 (440 4260);
PAINT ORANGE (440 4260);
FORCEPROP 2 LASTPIN (450 4200) $PN 69
J 2
(440 4210);
DISPLAY 0.617021 (440 4210);
PAINT ORANGE (440 4210);
FORCEPROP 2 LASTPIN (450 4150) $PN 213
J 2
(440 4160);
DISPLAY 0.617021 (440 4160);
PAINT ORANGE (440 4160);
FORCEPROP 2 LASTPIN (450 4100) $PN 214
J 2
(440 4110);
DISPLAY 0.617021 (440 4110);
PAINT ORANGE (440 4110);
FORCEPROP 2 LASTPIN (450 4050) $PN 71
J 2
(440 4060);
DISPLAY 0.617021 (440 4060);
PAINT ORANGE (440 4060);
FORCEPROP 2 LASTPIN (450 4000) $PN 216
J 2
(440 4010);
DISPLAY 0.617021 (440 4010);
PAINT ORANGE (440 4010);
FORCEPROP 2 LASTPIN (450 3950) $PN 72
J 2
(440 3960);
DISPLAY 0.617021 (440 3960);
PAINT ORANGE (440 3960);
FORCEPROP 2 LASTPIN (450 3900) $PN 79
J 2
(440 3910);
DISPLAY 0.617021 (440 3910);
PAINT ORANGE (440 3910);
FORCEPROP 2 LASTPIN (1450 4500) $PN 137
J 0
(1460 4510);
DISPLAY 0.617021 (1460 4510);
PAINT ORANGE (1460 4510);
FORCEPROP 2 LASTPIN (1450 3500) $PN 102
J 0
(1460 3510);
DISPLAY 0.617021 (1460 3510);
PAINT ORANGE (1460 3510);
FORCEPROP 2 LASTPIN (450 4650) $PN 86
J 2
(440 4660);
DISPLAY 0.617021 (440 4660);
PAINT ORANGE (440 4660);
FORCEPROP 1 LAST PART_NUMBER H44441-003
J 0
(500 1100);
DISPLAY 0.617021 (500 1100);
PAINT BLUE (500 1100);
FORCEPROP 2 LASTPIN (1450 4100) $PN 126
J 0
(1460 4110);
DISPLAY 0.617021 (1460 4110);
PAINT ORANGE (1460 4110);
FORCEPROP 2 LASTPIN (1450 4150) $PN 271
J 0
(1460 4160);
DISPLAY 0.617021 (1460 4160);
PAINT ORANGE (1460 4160);
FORCEPROP 2 LASTPIN (1450 4200) $PN 117
J 0
(1460 4210);
DISPLAY 0.617021 (1460 4210);
PAINT ORANGE (1460 4210);
FORCEPROP 2 LASTPIN (1450 4300) $PN 124
J 0
(1460 4310);
DISPLAY 0.617021 (1460 4310);
PAINT ORANGE (1460 4310);
FORCEPROP 1 LAST MATERIAL SCONN
J 0
(500 4950);
DISPLAY 0.617021 (500 4950);
PAINT SKYBLUE (500 4950);
FORCEPROP 1 LAST LOCATION J6M1
J 0
(500 5000);
DISPLAY 0.617021 (500 5000);
PAINT AQUA (500 5000);
FORCEPROP 2 LASTPIN (1450 4600) $PN 128
J 0
(1460 4610);
DISPLAY 0.617021 (1460 4610);
PAINT ORANGE (1460 4610);
FORCEPROP 2 LASTPIN (1450 4550) $PN 282
J 0
(1460 4560);
DISPLAY 0.617021 (1460 4560);
PAINT ORANGE (1460 4560);
FORCEPROP 0 LAST BOM_SS NOPOP
J 0
(685 4992);
DISPLAY 1.021277 (685 4992);
PAINT BROWN (685 4992);
DISPLAY BOTH (685 4992);
FORCEPROP 2 LASTPIN (1450 2450) $PN 172
J 0
(1460 2460);
DISPLAY 0.617021 (1460 2460);
PAINT ORANGE (1460 2460);
FORCEPROP 2 LASTPIN (1450 2400) $PN 27
J 0
(1460 2410);
DISPLAY 0.617021 (1460 2410);
PAINT ORANGE (1460 2410);
FORCEPROP 1 LAST PACK_TYPE PIP
J 0
(500 5050);
PAINT SKYBLUE (500 5050);
DISPLAY INVISIBLE (500 5050);
FORCEPROP 2 LAST BOM_COST MEM
J 0
(1000 2450);
PAINT ORANGE (1000 2450);
DISPLAY INVISIBLE (1000 2450);
FORCEPROP 2 LAST CDS_LIB mstr_sconn
J 0
(950 3100);
PAINT ORANGE (950 3100);
DISPLAY INVISIBLE (950 3100);
FORCEPROP 2 LAST SEC_TYPE PIP
J 0
(500 5050);
DISPLAY 1.021277 (500 5050);
PAINT ORANGE (500 5050);
DISPLAY INVISIBLE (500 5050);
FORCEPROP 2 LAST SEC 1
J 0
(500 5050);
DISPLAY 0.680851 (500 5050);
PAINT MONO (500 5050);
DISPLAY INVISIBLE (500 5050);
FORCEPROP 2 LAST CDS_LOCATION J6M1
J 0
(500 5000);
DISPLAY 0.617021 (500 5000);
PAINT AQUA (500 5000);
DISPLAY INVISIBLE (500 5000);
FORCEPROP 1 LAST PATH I158
J 0
(950 4950);
PAINT GREEN (950 4950);
DISPLAY INVISIBLE (950 4950);
FORCEPROP 2 LAST ROOM DDR4_CH_D
J 0
(1000 2450);
PAINT ORANGE (1000 2450);
DISPLAY INVISIBLE (1000 2450);
FORCEADD OFFPAGE..1
(-550 3850);
FORCEPROP 2 LAST $XR1 49 
J 0
(-861 3850);
DISPLAY 0.638298 (-861 3850);
PAINT MONO (-861 3850);
FORCEPROP 2 LAST $XR0 26 
J 0
(-771 3850);
DISPLAY 0.638298 (-771 3850);
PAINT MONO (-771 3850);
FORCEPROP 2 LAST CDS_LIB mstr_standard
J 0
(-550 3850);
DISPLAY 0.787234 (-550 3850);
PAINT MONO (-550 3850);
DISPLAY INVISIBLE (-550 3850);
FORCEPROP 1 LAST OFFPAGE TRUE
J 0
(-225 3725);
DISPLAY 0.936170 (-225 3725);
PAINT GREEN (-225 3725);
DISPLAY INVISIBLE (-225 3725);
FORCEPROP 1 LAST COMMENT_BODY TRUE
J 0
(-425 3750);
DISPLAY 0.936170 (-425 3750);
PAINT GREEN (-425 3750);
DISPLAY INVISIBLE (-425 3750);
FORCEPROP 2 LAST PATH I159
J 0
(-750 3900);
DISPLAY 1.021277 (-750 3900);
PAINT ORANGE (-750 3900);
DISPLAY INVISIBLE (-750 3900);
FORCEADD TAP..6
R 2
(4100 4300);
FORCEPROP 3 LASTPIN (4050 4300) SIG_NAME M_D_DQS_DP<12>
J 0
(4060 4310);
DISPLAY 0.659574 (4060 4310);
PAINT MONO (4060 4310);
DISPLAY INVISIBLE (4060 4310);
FORCEPROP 1 LASTPIN (4050 4300) BN 12
J 2
(4100 4310);
DISPLAY 0.617021 (4100 4310);
PAINT PINK (4100 4310);
FORCEPROP 2 LAST CDS_LIB mstr_standard
J 0
(4100 4300);
DISPLAY 0.787234 (4100 4300);
PAINT MONO (4100 4300);
DISPLAY INVISIBLE (4100 4300);
FORCEPROP 1 LAST BODY_TYPE PLUMBING
J 2
(4100 4250);
DISPLAY 1.234043 (4100 4250);
PAINT GREEN (4100 4250);
DISPLAY INVISIBLE (4100 4250);
FORCEPROP 1 LAST HDL_TAP TRUE
J 2
(3775 4175);
DISPLAY 1.234043 (3775 4175);
PAINT GREEN (3775 4175);
DISPLAY INVISIBLE (3775 4175);
FORCEPROP 1 LAST PATH I16
J 2
(4102 4300);
DISPLAY 0.872340 (4102 4300);
PAINT GREEN (4102 4300);
DISPLAY INVISIBLE (4102 4300);
FORCEADD OFFPAGE..1
(-550 3600);
FORCEPROP 2 LAST $XR1 49 
J 0
(-861 3600);
DISPLAY 0.638298 (-861 3600);
PAINT MONO (-861 3600);
FORCEPROP 2 LAST $XR0 26 
J 0
(-771 3600);
DISPLAY 0.638298 (-771 3600);
PAINT MONO (-771 3600);
FORCEPROP 2 LAST CDS_LIB mstr_standard
J 0
(-550 3600);
DISPLAY 0.787234 (-550 3600);
PAINT MONO (-550 3600);
DISPLAY INVISIBLE (-550 3600);
FORCEPROP 1 LAST OFFPAGE TRUE
J 0
(-225 3475);
DISPLAY 0.936170 (-225 3475);
PAINT GREEN (-225 3475);
DISPLAY INVISIBLE (-225 3475);
FORCEPROP 1 LAST COMMENT_BODY TRUE
J 0
(-425 3500);
DISPLAY 0.936170 (-425 3500);
PAINT GREEN (-425 3500);
DISPLAY INVISIBLE (-425 3500);
FORCEPROP 2 LAST PATH I160
J 0
(-750 3650);
DISPLAY 1.021277 (-750 3650);
PAINT ORANGE (-750 3650);
DISPLAY INVISIBLE (-750 3650);
FORCEADD OFFPAGE..1
(-550 3750);
FORCEPROP 2 LAST $XR1 49 
J 0
(-861 3750);
DISPLAY 0.638298 (-861 3750);
PAINT MONO (-861 3750);
FORCEPROP 2 LAST $XR0 26 
J 0
(-771 3750);
DISPLAY 0.638298 (-771 3750);
PAINT MONO (-771 3750);
FORCEPROP 2 LAST CDS_LIB mstr_standard
J 0
(-550 3750);
DISPLAY 0.787234 (-550 3750);
PAINT MONO (-550 3750);
DISPLAY INVISIBLE (-550 3750);
FORCEPROP 1 LAST OFFPAGE TRUE
J 0
(-225 3625);
DISPLAY 0.936170 (-225 3625);
PAINT GREEN (-225 3625);
DISPLAY INVISIBLE (-225 3625);
FORCEPROP 1 LAST COMMENT_BODY TRUE
J 0
(-425 3650);
DISPLAY 0.936170 (-425 3650);
PAINT GREEN (-425 3650);
DISPLAY INVISIBLE (-425 3650);
FORCEPROP 2 LAST PATH I161
J 0
(-750 3800);
DISPLAY 1.021277 (-750 3800);
PAINT ORANGE (-750 3800);
DISPLAY INVISIBLE (-750 3800);
FORCEADD OFFPAGE..1
(-550 3550);
FORCEPROP 2 LAST $XR1 49 
J 0
(-861 3550);
DISPLAY 0.638298 (-861 3550);
PAINT MONO (-861 3550);
FORCEPROP 2 LAST $XR0 26 
J 0
(-771 3550);
DISPLAY 0.638298 (-771 3550);
PAINT MONO (-771 3550);
FORCEPROP 2 LAST CDS_LIB mstr_standard
J 0
(-550 3550);
DISPLAY 0.787234 (-550 3550);
PAINT MONO (-550 3550);
DISPLAY INVISIBLE (-550 3550);
FORCEPROP 1 LAST OFFPAGE TRUE
J 0
(-225 3425);
DISPLAY 0.936170 (-225 3425);
PAINT GREEN (-225 3425);
DISPLAY INVISIBLE (-225 3425);
FORCEPROP 1 LAST COMMENT_BODY TRUE
J 0
(-425 3450);
DISPLAY 0.936170 (-425 3450);
PAINT GREEN (-425 3450);
DISPLAY INVISIBLE (-425 3450);
FORCEPROP 2 LAST PATH I162
J 0
(-750 3600);
DISPLAY 1.021277 (-750 3600);
PAINT ORANGE (-750 3600);
DISPLAY INVISIBLE (-750 3600);
FORCEADD OFFPAGE..1
(-550 3350);
FORCEPROP 2 LAST $XR1 49 
J 0
(-861 3350);
DISPLAY 0.638298 (-861 3350);
PAINT MONO (-861 3350);
FORCEPROP 2 LAST $XR0 26 
J 0
(-771 3350);
DISPLAY 0.638298 (-771 3350);
PAINT MONO (-771 3350);
FORCEPROP 2 LAST CDS_LIB mstr_standard
J 0
(-550 3350);
DISPLAY 0.787234 (-550 3350);
PAINT MONO (-550 3350);
DISPLAY INVISIBLE (-550 3350);
FORCEPROP 1 LAST OFFPAGE TRUE
J 0
(-225 3225);
DISPLAY 0.936170 (-225 3225);
PAINT GREEN (-225 3225);
DISPLAY INVISIBLE (-225 3225);
FORCEPROP 1 LAST COMMENT_BODY TRUE
J 0
(-425 3250);
DISPLAY 0.936170 (-425 3250);
PAINT GREEN (-425 3250);
DISPLAY INVISIBLE (-425 3250);
FORCEPROP 2 LAST PATH I163
J 0
(-750 3400);
DISPLAY 1.021277 (-750 3400);
PAINT ORANGE (-750 3400);
DISPLAY INVISIBLE (-750 3400);
FORCEADD OFFPAGE..1
(-550 3300);
FORCEPROP 2 LAST $XR1 49 
J 0
(-861 3300);
DISPLAY 0.638298 (-861 3300);
PAINT MONO (-861 3300);
FORCEPROP 2 LAST $XR0 26 
J 0
(-771 3300);
DISPLAY 0.638298 (-771 3300);
PAINT MONO (-771 3300);
FORCEPROP 2 LAST CDS_LIB mstr_standard
J 0
(-550 3300);
DISPLAY 0.787234 (-550 3300);
PAINT MONO (-550 3300);
DISPLAY INVISIBLE (-550 3300);
FORCEPROP 1 LAST OFFPAGE TRUE
J 0
(-225 3175);
DISPLAY 0.936170 (-225 3175);
PAINT GREEN (-225 3175);
DISPLAY INVISIBLE (-225 3175);
FORCEPROP 1 LAST COMMENT_BODY TRUE
J 0
(-425 3200);
DISPLAY 0.936170 (-425 3200);
PAINT GREEN (-425 3200);
DISPLAY INVISIBLE (-425 3200);
FORCEPROP 2 LAST PATH I164
J 0
(-750 3350);
DISPLAY 1.021277 (-750 3350);
PAINT ORANGE (-750 3350);
DISPLAY INVISIBLE (-750 3350);
FORCEADD OFFPAGE..1
(-550 3050);
FORCEPROP 2 LAST $XR1 49 
J 0
(-861 3050);
DISPLAY 0.638298 (-861 3050);
PAINT MONO (-861 3050);
FORCEPROP 2 LAST $XR0 26 
J 0
(-771 3050);
DISPLAY 0.638298 (-771 3050);
PAINT MONO (-771 3050);
FORCEPROP 2 LAST CDS_LIB mstr_standard
J 0
(-550 3050);
DISPLAY 0.787234 (-550 3050);
PAINT MONO (-550 3050);
DISPLAY INVISIBLE (-550 3050);
FORCEPROP 1 LAST OFFPAGE TRUE
J 0
(-225 2925);
DISPLAY 0.936170 (-225 2925);
PAINT GREEN (-225 2925);
DISPLAY INVISIBLE (-225 2925);
FORCEPROP 1 LAST COMMENT_BODY TRUE
J 0
(-425 2950);
DISPLAY 0.936170 (-425 2950);
PAINT GREEN (-425 2950);
DISPLAY INVISIBLE (-425 2950);
FORCEPROP 2 LAST PATH I165
J 0
(-750 3100);
DISPLAY 1.021277 (-750 3100);
PAINT ORANGE (-750 3100);
DISPLAY INVISIBLE (-750 3100);
FORCEADD OFFPAGE..1
(-550 2900);
FORCEPROP 2 LAST $XR1 49 
J 0
(-861 2900);
DISPLAY 0.638298 (-861 2900);
PAINT MONO (-861 2900);
FORCEPROP 2 LAST $XR0 26 
J 0
(-771 2900);
DISPLAY 0.638298 (-771 2900);
PAINT MONO (-771 2900);
FORCEPROP 2 LAST CDS_LIB mstr_standard
J 0
(-550 2900);
DISPLAY 0.787234 (-550 2900);
PAINT MONO (-550 2900);
DISPLAY INVISIBLE (-550 2900);
FORCEPROP 1 LAST OFFPAGE TRUE
J 0
(-225 2775);
DISPLAY 0.936170 (-225 2775);
PAINT GREEN (-225 2775);
DISPLAY INVISIBLE (-225 2775);
FORCEPROP 1 LAST COMMENT_BODY TRUE
J 0
(-425 2800);
DISPLAY 0.936170 (-425 2800);
PAINT GREEN (-425 2800);
DISPLAY INVISIBLE (-425 2800);
FORCEPROP 2 LAST PATH I166
J 0
(-750 2950);
DISPLAY 1.021277 (-750 2950);
PAINT ORANGE (-750 2950);
DISPLAY INVISIBLE (-750 2950);
FORCEADD OFFPAGE..1
(-550 2700);
FORCEPROP 2 LAST $XR1 49 
J 0
(-891 2700);
DISPLAY 0.638298 (-891 2700);
PAINT MONO (-891 2700);
FORCEPROP 2 LAST $XR0 26 
J 0
(-801 2700);
DISPLAY 0.638298 (-801 2700);
PAINT MONO (-801 2700);
FORCEPROP 2 LAST CDS_LIB mstr_standard
J 0
(-550 2700);
DISPLAY 0.787234 (-550 2700);
PAINT MONO (-550 2700);
DISPLAY INVISIBLE (-550 2700);
FORCEPROP 1 LAST OFFPAGE TRUE
J 0
(-225 2575);
DISPLAY 0.936170 (-225 2575);
PAINT GREEN (-225 2575);
DISPLAY INVISIBLE (-225 2575);
FORCEPROP 1 LAST COMMENT_BODY TRUE
J 0
(-425 2600);
DISPLAY 0.936170 (-425 2600);
PAINT GREEN (-425 2600);
DISPLAY INVISIBLE (-425 2600);
FORCEPROP 2 LAST PATH I167
J 0
(-800 2750);
DISPLAY 1.021277 (-800 2750);
PAINT ORANGE (-800 2750);
DISPLAY INVISIBLE (-800 2750);
FORCEADD OFFPAGE..6
(-550 2750);
FORCEPROP 2 LAST $XR1 49 
J 0
(-889 2750);
DISPLAY 0.638298 (-889 2750);
PAINT MONO (-889 2750);
FORCEPROP 2 LAST $XR0 26 
J 0
(-799 2750);
DISPLAY 0.638298 (-799 2750);
PAINT MONO (-799 2750);
FORCEPROP 2 LAST CDS_LIB mstr_standard
J 0
(-550 2750);
DISPLAY 0.787234 (-550 2750);
PAINT MONO (-550 2750);
DISPLAY INVISIBLE (-550 2750);
FORCEPROP 1 LAST OFFPAGE TRUE
J 0
(-225 2625);
DISPLAY 0.936170 (-225 2625);
PAINT GREEN (-225 2625);
DISPLAY INVISIBLE (-225 2625);
FORCEPROP 1 LAST COMMENT_BODY TRUE
J 0
(-450 2675);
DISPLAY 0.936170 (-450 2675);
PAINT GREEN (-450 2675);
DISPLAY INVISIBLE (-450 2675);
FORCEPROP 2 LAST PATH I168
J 0
(-775 2800);
DISPLAY 1.021277 (-775 2800);
PAINT ORANGE (-775 2800);
DISPLAY INVISIBLE (-775 2800);
FORCEADD OFFPAGE..1
(-550 2650);
FORCEPROP 2 LAST $XR5 54 
J 0
(-1221 2650);
DISPLAY 0.638298 (-1221 2650);
PAINT MONO (-1221 2650);
FORCEPROP 2 LAST $XR4 53 
J 0
(-1131 2650);
DISPLAY 0.638298 (-1131 2650);
PAINT MONO (-1131 2650);
FORCEPROP 2 LAST $XR3 52 
J 0
(-1041 2650);
DISPLAY 0.638298 (-1041 2650);
PAINT MONO (-1041 2650);
FORCEPROP 2 LAST $XR2 51 
J 0
(-951 2650);
DISPLAY 0.638298 (-951 2650);
PAINT MONO (-951 2650);
FORCEPROP 2 LAST $XR1 49 
J 0
(-861 2650);
DISPLAY 0.638298 (-861 2650);
PAINT MONO (-861 2650);
FORCEPROP 2 LAST $XR0 21 
J 0
(-771 2650);
DISPLAY 0.638298 (-771 2650);
PAINT MONO (-771 2650);
FORCEPROP 2 LAST CDS_LIB mstr_standard
J 0
(-550 2650);
DISPLAY 0.787234 (-550 2650);
PAINT MONO (-550 2650);
DISPLAY INVISIBLE (-550 2650);
FORCEPROP 1 LAST OFFPAGE TRUE
J 0
(-225 2525);
DISPLAY 0.936170 (-225 2525);
PAINT GREEN (-225 2525);
DISPLAY INVISIBLE (-225 2525);
FORCEPROP 1 LAST COMMENT_BODY TRUE
J 0
(-425 2550);
DISPLAY 0.936170 (-425 2550);
PAINT GREEN (-425 2550);
DISPLAY INVISIBLE (-425 2550);
FORCEPROP 2 LAST PATH I169
J 0
(-725 2700);
DISPLAY 1.021277 (-725 2700);
PAINT ORANGE (-725 2700);
DISPLAY INVISIBLE (-725 2700);
FORCEADD TAP..6
R 2
(4100 4200);
FORCEPROP 3 LASTPIN (4050 4200) SIG_NAME M_D_DQS_DP<11>
J 0
(4060 4210);
DISPLAY 0.659574 (4060 4210);
PAINT MONO (4060 4210);
DISPLAY INVISIBLE (4060 4210);
FORCEPROP 1 LASTPIN (4050 4200) BN 11
J 2
(4100 4210);
DISPLAY 0.617021 (4100 4210);
PAINT PINK (4100 4210);
FORCEPROP 2 LAST CDS_LIB mstr_standard
J 0
(4100 4200);
DISPLAY 0.787234 (4100 4200);
PAINT MONO (4100 4200);
DISPLAY INVISIBLE (4100 4200);
FORCEPROP 1 LAST BODY_TYPE PLUMBING
J 2
(4100 4150);
DISPLAY 1.234043 (4100 4150);
PAINT GREEN (4100 4150);
DISPLAY INVISIBLE (4100 4150);
FORCEPROP 1 LAST HDL_TAP TRUE
J 2
(3775 4075);
DISPLAY 1.234043 (3775 4075);
PAINT GREEN (3775 4075);
DISPLAY INVISIBLE (3775 4075);
FORCEPROP 1 LAST PATH I17
J 2
(4102 4200);
DISPLAY 0.872340 (4102 4200);
PAINT GREEN (4102 4200);
DISPLAY INVISIBLE (4102 4200);
FORCEADD OFFPAGE..5
(-575 2100);
FORCEPROP 2 LAST $XR1 26 
J 0
(-889 2100);
DISPLAY 0.638298 (-889 2100);
PAINT MONO (-889 2100);
FORCEPROP 2 LAST $XR0 49 
J 0
(-799 2100);
DISPLAY 0.638298 (-799 2100);
PAINT MONO (-799 2100);
FORCEPROP 2 LAST CDS_LIB mstr_standard
J 0
(-575 2100);
DISPLAY 0.787234 (-575 2100);
PAINT MONO (-575 2100);
DISPLAY INVISIBLE (-575 2100);
FORCEPROP 1 LAST OFFPAGE TRUE
J 0
(-250 1975);
DISPLAY 1.404255 (-250 1975);
PAINT GREEN (-250 1975);
DISPLAY INVISIBLE (-250 1975);
FORCEPROP 1 LAST COMMENT_BODY TRUE
J 0
(-475 2025);
DISPLAY 1.404255 (-475 2025);
PAINT GREEN (-475 2025);
DISPLAY INVISIBLE (-475 2025);
FORCEPROP 2 LAST PATH I170
J 0
(-775 2150);
DISPLAY 1.021277 (-775 2150);
PAINT ORANGE (-775 2150);
DISPLAY INVISIBLE (-775 2150);
FORCEADD OFFPAGE..5
(-775 2450);
FORCEPROP 2 LAST $XR23 94 
J 0
(-1269 2486);
DISPLAY 0.638298 (-1269 2486);
PAINT MONO (-1269 2486);
FORCEPROP 2 LAST $XR22 88 
J 0
(-1179 2486);
DISPLAY 0.638298 (-1179 2486);
PAINT MONO (-1179 2486);
FORCEPROP 2 LAST $XR21 87 
J 0
(-1089 2486);
DISPLAY 0.638298 (-1089 2486);
PAINT MONO (-1089 2486);
FORCEPROP 2 LAST $XR20 86 
J 0
(-999 2486);
DISPLAY 0.638298 (-999 2486);
PAINT MONO (-999 2486);
FORCEPROP 2 LAST $XR19 85 
J 0
(-1809 2414);
DISPLAY 0.638298 (-1809 2414);
PAINT MONO (-1809 2414);
FORCEPROP 2 LAST $XR18 84 
J 0
(-1719 2414);
DISPLAY 0.638298 (-1719 2414);
PAINT MONO (-1719 2414);
FORCEPROP 2 LAST $XR17 83 
J 0
(-1629 2414);
DISPLAY 0.638298 (-1629 2414);
PAINT MONO (-1629 2414);
FORCEPROP 2 LAST $XR16 82 
J 0
(-1539 2414);
DISPLAY 0.638298 (-1539 2414);
PAINT MONO (-1539 2414);
FORCEPROP 2 LAST $XR15 81 
J 0
(-1449 2414);
DISPLAY 0.638298 (-1449 2414);
PAINT MONO (-1449 2414);
FORCEPROP 2 LAST $XR14 80 
J 0
(-1359 2414);
DISPLAY 0.638298 (-1359 2414);
PAINT MONO (-1359 2414);
FORCEPROP 2 LAST $XR13 79 
J 0
(-1269 2414);
DISPLAY 0.638298 (-1269 2414);
PAINT MONO (-1269 2414);
FORCEPROP 2 LAST $XR12 78 
J 0
(-1179 2414);
DISPLAY 0.638298 (-1179 2414);
PAINT MONO (-1179 2414);
FORCEPROP 2 LAST $XR11 77 
J 0
(-1089 2414);
DISPLAY 0.638298 (-1089 2414);
PAINT MONO (-1089 2414);
FORCEPROP 2 LAST $XR10 54 
J 0
(-999 2414);
DISPLAY 0.638298 (-999 2414);
PAINT MONO (-999 2414);
FORCEPROP 2 LAST $XR9 53 
J 0
(-1809 2450);
DISPLAY 0.638298 (-1809 2450);
PAINT MONO (-1809 2450);
FORCEPROP 2 LAST $XR8 52 
J 0
(-1719 2450);
DISPLAY 0.638298 (-1719 2450);
PAINT MONO (-1719 2450);
FORCEPROP 2 LAST $XR7 51 
J 0
(-1629 2450);
DISPLAY 0.638298 (-1629 2450);
PAINT MONO (-1629 2450);
FORCEPROP 2 LAST $XR6 49 
J 0
(-1539 2450);
DISPLAY 0.638298 (-1539 2450);
PAINT MONO (-1539 2450);
FORCEPROP 2 LAST $XR5 48 
J 0
(-1449 2450);
DISPLAY 0.638298 (-1449 2450);
PAINT MONO (-1449 2450);
FORCEPROP 2 LAST $XR4 47 
J 0
(-1359 2450);
DISPLAY 0.638298 (-1359 2450);
PAINT MONO (-1359 2450);
FORCEPROP 2 LAST $XR3 46 
J 0
(-1269 2450);
DISPLAY 0.638298 (-1269 2450);
PAINT MONO (-1269 2450);
FORCEPROP 2 LAST $XR2 45 
J 0
(-1179 2450);
DISPLAY 0.638298 (-1179 2450);
PAINT MONO (-1179 2450);
FORCEPROP 2 LAST $XR1 44 
J 0
(-1089 2450);
DISPLAY 0.638298 (-1089 2450);
PAINT MONO (-1089 2450);
FORCEPROP 2 LAST $XR0 43 
J 0
(-999 2450);
DISPLAY 0.638298 (-999 2450);
PAINT MONO (-999 2450);
FORCEPROP 2 LAST CDS_LIB mstr_standard
J 0
(-775 2450);
DISPLAY 0.787234 (-775 2450);
PAINT MONO (-775 2450);
DISPLAY INVISIBLE (-775 2450);
FORCEPROP 1 LAST OFFPAGE TRUE
J 0
(-450 2325);
DISPLAY 1.404255 (-450 2325);
PAINT GREEN (-450 2325);
DISPLAY INVISIBLE (-450 2325);
FORCEPROP 1 LAST COMMENT_BODY TRUE
J 0
(-675 2375);
DISPLAY 1.404255 (-675 2375);
PAINT GREEN (-675 2375);
DISPLAY INVISIBLE (-675 2375);
FORCEPROP 2 LAST PATH I171
J 0
(-975 2525);
DISPLAY 1.021277 (-975 2525);
PAINT ORANGE (-975 2525);
DISPLAY INVISIBLE (-975 2525);
FORCEADD PVPP_DEF..1
(-1650 2100);
FORCEPROP 3 LASTPIN (-1650 2050) SIG_NAME PVPP_DEF\g
J 0
(-1640 2060);
DISPLAY 0.659574 (-1640 2060);
PAINT MONO (-1640 2060);
DISPLAY INVISIBLE (-1640 2060);
FORCEPROP 1 LAST VOLTAGE 2.5V
J 0
(-1695 2057);
DISPLAY 0.340426 (-1695 2057);
PAINT SKYBLUE (-1695 2057);
DISPLAY INVISIBLE (-1695 2057);
FORCEPROP 0 LAST BOM_COST MEM
J 0
(-1650 2200);
PAINT ORANGE (-1650 2200);
DISPLAY INVISIBLE (-1650 2200);
FORCEPROP 2 LAST CDS_LIB mstr_symbols
J 0
(-1650 2100);
PAINT ORANGE (-1650 2100);
DISPLAY INVISIBLE (-1650 2100);
FORCEPROP 1 LAST BODY_TYPE PLUMBING
J 0
(-1695 2057);
DISPLAY 0.340426 (-1695 2057);
PAINT GREEN (-1695 2057);
DISPLAY INVISIBLE (-1695 2057);
FORCEPROP 1 LAST PATH I172
J 0
(-1600 2125);
DISPLAY 0.872340 (-1600 2125);
PAINT AQUA (-1600 2125);
DISPLAY INVISIBLE (-1600 2125);
FORCEPROP 2 LAST ROOM DDR4_CH_B
J 0
(-1650 2200);
PAINT ORANGE (-1650 2200);
DISPLAY INVISIBLE (-1650 2200);
FORCEPROP 1 LAST HDL_POWER PVPP_DEF
J 1
(-1650 2150);
DISPLAY 0.872340 (-1650 2150);
PAINT GREEN (-1650 2150);
DISPLAY INVISIBLE (-1650 2150);
FORCEADD OFFPAGE..1
(-550 2050);
FORCEPROP 2 LAST $XR1 49 
J 0
(-891 2050);
DISPLAY 0.638298 (-891 2050);
PAINT MONO (-891 2050);
FORCEPROP 2 LAST $XR0 26 
J 0
(-801 2050);
DISPLAY 0.638298 (-801 2050);
PAINT MONO (-801 2050);
FORCEPROP 2 LAST CDS_LIB mstr_standard
J 0
(-550 2050);
DISPLAY 0.787234 (-550 2050);
PAINT MONO (-550 2050);
DISPLAY INVISIBLE (-550 2050);
FORCEPROP 1 LAST OFFPAGE TRUE
J 0
(-225 1925);
DISPLAY 0.936170 (-225 1925);
PAINT GREEN (-225 1925);
DISPLAY INVISIBLE (-225 1925);
FORCEPROP 1 LAST COMMENT_BODY TRUE
J 0
(-425 1950);
DISPLAY 0.936170 (-425 1950);
PAINT GREEN (-425 1950);
DISPLAY INVISIBLE (-425 1950);
FORCEPROP 2 LAST PATH I173
J 0
(-800 2100);
DISPLAY 1.021277 (-800 2100);
PAINT ORANGE (-800 2100);
DISPLAY INVISIBLE (-800 2100);
FORCEADD OFFPAGE..6
(-400 1750);
FORCEPROP 2 LASTPIN (-350 1750) SIG_NAME SMB_DDR_DEF_VPP_SDA
J 0
(-310 1760);
DISPLAY 0.617021 (-310 1760);
PAINT ORANGE (-310 1760);
FORCEPROP 2 LAST $XR5 99 
J 0
(-1099 1750);
DISPLAY 0.638298 (-1099 1750);
PAINT MONO (-1099 1750);
FORCEPROP 2 LAST $XR4 54 
J 0
(-1009 1750);
DISPLAY 0.638298 (-1009 1750);
PAINT MONO (-1009 1750);
FORCEPROP 2 LAST $XR3 53 
J 0
(-919 1750);
DISPLAY 0.638298 (-919 1750);
PAINT MONO (-919 1750);
FORCEPROP 2 LAST $XR2 52 
J 0
(-829 1750);
DISPLAY 0.638298 (-829 1750);
PAINT MONO (-829 1750);
FORCEPROP 2 LAST $XR1 51 
J 0
(-739 1750);
DISPLAY 0.638298 (-739 1750);
PAINT MONO (-739 1750);
FORCEPROP 2 LAST $XR0 49 
J 0
(-649 1750);
DISPLAY 0.638298 (-649 1750);
PAINT MONO (-649 1750);
FORCEPROP 2 LAST CDS_LIB mstr_standard
J 0
(-400 1750);
DISPLAY 0.787234 (-400 1750);
PAINT MONO (-400 1750);
DISPLAY INVISIBLE (-400 1750);
FORCEPROP 1 LAST OFFPAGE TRUE
J 0
(-75 1625);
DISPLAY 0.936170 (-75 1625);
PAINT GREEN (-75 1625);
DISPLAY INVISIBLE (-75 1625);
FORCEPROP 1 LAST COMMENT_BODY TRUE
J 0
(-300 1675);
DISPLAY 0.936170 (-300 1675);
PAINT GREEN (-300 1675);
DISPLAY INVISIBLE (-300 1675);
FORCEPROP 2 LAST PATH I174
J 0
(-625 1800);
DISPLAY 1.021277 (-625 1800);
PAINT ORANGE (-625 1800);
DISPLAY INVISIBLE (-625 1800);
FORCEADD OFFPAGE..1
(-400 1700);
FORCEPROP 2 LAST $XR5 54 
J 0
(-1101 1700);
DISPLAY 0.638298 (-1101 1700);
PAINT MONO (-1101 1700);
FORCEPROP 2 LAST $XR4 53 
J 0
(-1011 1700);
DISPLAY 0.638298 (-1011 1700);
PAINT MONO (-1011 1700);
FORCEPROP 2 LAST $XR3 52 
J 0
(-921 1700);
DISPLAY 0.638298 (-921 1700);
PAINT MONO (-921 1700);
FORCEPROP 2 LAST $XR2 51 
J 0
(-831 1700);
DISPLAY 0.638298 (-831 1700);
PAINT MONO (-831 1700);
FORCEPROP 2 LAST $XR1 49 
J 0
(-741 1700);
DISPLAY 0.638298 (-741 1700);
PAINT MONO (-741 1700);
FORCEPROP 2 LAST $XR0 99 
J 0
(-651 1700);
DISPLAY 0.638298 (-651 1700);
PAINT MONO (-651 1700);
FORCEPROP 2 LAST CDS_LIB mstr_standard
J 0
(-400 1700);
DISPLAY 0.787234 (-400 1700);
PAINT MONO (-400 1700);
DISPLAY INVISIBLE (-400 1700);
FORCEPROP 1 LAST OFFPAGE TRUE
J 0
(-75 1575);
DISPLAY 0.936170 (-75 1575);
PAINT GREEN (-75 1575);
DISPLAY INVISIBLE (-75 1575);
FORCEPROP 1 LAST COMMENT_BODY TRUE
J 0
(-275 1600);
DISPLAY 0.936170 (-275 1600);
PAINT GREEN (-275 1600);
DISPLAY INVISIBLE (-275 1600);
FORCEPROP 2 LAST PATH I175
J 0
(-650 1750);
DISPLAY 1.021277 (-650 1750);
PAINT ORANGE (-650 1750);
DISPLAY INVISIBLE (-650 1750);
FORCEADD OFFPAGE..1
(-450 1300);
FORCEPROP 2 LAST $XR5 54 
J 0
(-1121 1300);
DISPLAY 0.638298 (-1121 1300);
PAINT MONO (-1121 1300);
FORCEPROP 2 LAST $XR4 53 
J 0
(-1031 1300);
DISPLAY 0.638298 (-1031 1300);
PAINT MONO (-1031 1300);
FORCEPROP 2 LAST $XR3 52 
J 0
(-941 1300);
DISPLAY 0.638298 (-941 1300);
PAINT MONO (-941 1300);
FORCEPROP 2 LAST $XR2 51 
J 0
(-851 1300);
DISPLAY 0.638298 (-851 1300);
PAINT MONO (-851 1300);
FORCEPROP 2 LAST $XR1 49 
J 0
(-761 1300);
DISPLAY 0.638298 (-761 1300);
PAINT MONO (-761 1300);
FORCEPROP 2 LAST $XR0 89 
J 0
(-671 1300);
DISPLAY 0.638298 (-671 1300);
PAINT MONO (-671 1300);
FORCEPROP 2 LAST CDS_LIB mstr_standard
J 0
(-450 1300);
PAINT ORANGE (-450 1300);
DISPLAY INVISIBLE (-450 1300);
FORCEPROP 1 LAST OFFPAGE TRUE
J 0
(-125 1175);
DISPLAY 0.936170 (-125 1175);
PAINT GREEN (-125 1175);
DISPLAY INVISIBLE (-125 1175);
FORCEPROP 1 LAST COMMENT_BODY TRUE
J 0
(-325 1200);
DISPLAY 0.936170 (-325 1200);
PAINT GREEN (-325 1200);
DISPLAY INVISIBLE (-325 1200);
FORCEPROP 2 LAST PATH I176
J 0
(-700 1350);
DISPLAY 1.021277 (-700 1350);
PAINT ORANGE (-700 1350);
DISPLAY INVISIBLE (-700 1350);
FORCEADD CAP_A..1
R 2
(-1200 1400);
FORCEPROP 1 LAST LOCATION C6M1
J 2
(-1250 1500);
DISPLAY 0.617021 (-1250 1500);
PAINT AQUA (-1250 1500);
FORCEPROP 1 LAST VALUE 0.01UF
J 2
(-1250 1450);
DISPLAY 0.617021 (-1250 1450);
PAINT SKYBLUE (-1250 1450);
FORCEPROP 1 LAST VOLTAGE 25V
J 2
(-1250 1400);
DISPLAY 0.617021 (-1250 1400);
PAINT SKYBLUE (-1250 1400);
FORCEPROP 1 LAST PART_NUMBER A36096-045
J 2
(-1250 1250);
DISPLAY 0.617021 (-1250 1250);
PAINT BLUE (-1250 1250);
FORCEPROP 1 LAST MATERIAL X7R
J 2
(-1250 1300);
DISPLAY 0.617021 (-1250 1300);
PAINT SKYBLUE (-1250 1300);
FORCEPROP 1 LAST TOLERANCE 10%
J 2
(-1250 1350);
DISPLAY 0.617021 (-1250 1350);
PAINT SKYBLUE (-1250 1350);
FORCEPROP 1 LAST PACK_TYPE 0402V
J 2
(-1250 1200);
DISPLAY 0.617021 (-1250 1200);
PAINT SKYBLUE (-1250 1200);
FORCEPROP 1 LASTPIN (-1200 1300) $PN 2
J 2
(-1210 1280);
DISPLAY 0.787234 (-1210 1280);
PAINT ORANGE (-1210 1280);
FORCEPROP 1 LASTPIN (-1200 1500) $PN 1
J 2
(-1210 1480);
DISPLAY 0.787234 (-1210 1480);
PAINT ORANGE (-1210 1480);
FORCEPROP 2 LAST CDS_LOCATION C6M1
J 2
(-1250 1500);
DISPLAY 0.617021 (-1250 1500);
PAINT AQUA (-1250 1500);
DISPLAY INVISIBLE (-1250 1500);
FORCEPROP 2 LAST BOM_COST MEM
J 0
(-1200 1400);
PAINT ORANGE (-1200 1400);
DISPLAY INVISIBLE (-1200 1400);
FORCEPROP 2 LAST CDS_LIB dev_discrete
J 0
(-1200 1400);
PAINT ORANGE (-1200 1400);
DISPLAY INVISIBLE (-1200 1400);
FORCEPROP 1 LAST PATH I177
J 2
(-1250 1550);
DISPLAY 0.978723 (-1250 1550);
PAINT WHITE (-1250 1550);
DISPLAY INVISIBLE (-1250 1550);
FORCEPROP 2 LAST ROOM DDR4_CH_B
J 0
(-1200 1400);
PAINT ORANGE (-1200 1400);
DISPLAY INVISIBLE (-1200 1400);
FORCEPROP 2 LAST SEC 1
J 0
(-1250 1600);
PAINT MONO (-1250 1600);
DISPLAY INVISIBLE (-1250 1600);
FORCEPROP 2 LAST SEC_TYPE 0402V
J 0
(-1250 1600);
DISPLAY 1.021277 (-1250 1600);
PAINT ORANGE (-1250 1600);
DISPLAY INVISIBLE (-1250 1600);
FORCEADD GND..1
(-1200 1150);
FORCEPROP 3 LASTPIN (-1200 1200) SIG_NAME GND\g
J 0
(-1190 1210);
DISPLAY 0.659574 (-1190 1210);
PAINT MONO (-1190 1210);
DISPLAY INVISIBLE (-1190 1210);
FORCEPROP 1 LAST VOLTAGE 0
J 0
(-1200 1150);
PAINT SKYBLUE (-1200 1150);
DISPLAY INVISIBLE (-1200 1150);
FORCEPROP 2 LAST CDS_LIB mstr_symbols
J 0
(-1200 1150);
PAINT ORANGE (-1200 1150);
DISPLAY INVISIBLE (-1200 1150);
FORCEPROP 1 LAST SIZE 1B
J 0
(-1125 1100);
DISPLAY 1.787234 (-1125 1100);
PAINT GREEN (-1125 1100);
DISPLAY INVISIBLE (-1125 1100);
FORCEPROP 2 LAST BOM_COST MEM
J 0
(-1200 1155);
PAINT ORANGE (-1200 1155);
DISPLAY INVISIBLE (-1200 1155);
FORCEPROP 1 LAST BODY_TYPE PLUMBING
J 0
(-1245 1107);
DISPLAY 0.340426 (-1245 1107);
PAINT GREEN (-1245 1107);
DISPLAY INVISIBLE (-1245 1107);
FORCEPROP 1 LAST PATH I178
J 0
(-1125 1150);
DISPLAY 0.872340 (-1125 1150);
PAINT AQUA (-1125 1150);
DISPLAY INVISIBLE (-1125 1150);
FORCEPROP 2 LAST ROOM DDR4_CH_B
J 0
(-1200 1155);
PAINT ORANGE (-1200 1155);
DISPLAY INVISIBLE (-1200 1155);
FORCEPROP 1 LAST HDL_POWER GND
J 0
(-1200 1300);
DISPLAY 1.404255 (-1200 1300);
PAINT GREEN (-1200 1300);
DISPLAY INVISIBLE (-1200 1300);
FORCEADD OFFPAGE..1
(-1350 1600);
FORCEPROP 2 LAST $XR1 49 
J 0
(-1661 1600);
DISPLAY 0.638298 (-1661 1600);
PAINT MONO (-1661 1600);
FORCEPROP 2 LAST $XR0 98 
J 0
(-1571 1600);
DISPLAY 0.638298 (-1571 1600);
PAINT MONO (-1571 1600);
FORCEPROP 2 LAST CDS_LIB mstr_standard
J 0
(-1350 1600);
DISPLAY 0.787234 (-1350 1600);
PAINT MONO (-1350 1600);
DISPLAY INVISIBLE (-1350 1600);
FORCEPROP 1 LAST OFFPAGE TRUE
J 0
(-1025 1475);
DISPLAY 0.936170 (-1025 1475);
PAINT GREEN (-1025 1475);
DISPLAY INVISIBLE (-1025 1475);
FORCEPROP 1 LAST COMMENT_BODY TRUE
J 0
(-1225 1500);
DISPLAY 0.936170 (-1225 1500);
PAINT GREEN (-1225 1500);
DISPLAY INVISIBLE (-1225 1500);
FORCEPROP 2 LAST PATH I179
J 0
(-1550 1650);
DISPLAY 1.021277 (-1550 1650);
PAINT ORANGE (-1550 1650);
DISPLAY INVISIBLE (-1550 1650);
FORCEADD TAP..6
R 2
(4100 4100);
FORCEPROP 3 LASTPIN (4050 4100) SIG_NAME M_D_DQS_DP<10>
J 0
(4060 4110);
DISPLAY 0.659574 (4060 4110);
PAINT MONO (4060 4110);
DISPLAY INVISIBLE (4060 4110);
FORCEPROP 1 LASTPIN (4050 4100) BN 10
J 2
(4100 4110);
DISPLAY 0.617021 (4100 4110);
PAINT PINK (4100 4110);
FORCEPROP 2 LAST CDS_LIB mstr_standard
J 0
(4100 4100);
DISPLAY 0.787234 (4100 4100);
PAINT MONO (4100 4100);
DISPLAY INVISIBLE (4100 4100);
FORCEPROP 1 LAST BODY_TYPE PLUMBING
J 2
(4100 4050);
DISPLAY 1.234043 (4100 4050);
PAINT GREEN (4100 4050);
DISPLAY INVISIBLE (4100 4050);
FORCEPROP 1 LAST HDL_TAP TRUE
J 2
(3775 3975);
DISPLAY 1.234043 (3775 3975);
PAINT GREEN (3775 3975);
DISPLAY INVISIBLE (3775 3975);
FORCEPROP 1 LAST PATH I18
J 2
(4102 4100);
DISPLAY 0.872340 (4102 4100);
PAINT GREEN (4102 4100);
DISPLAY INVISIBLE (4102 4100);
FORCEADD GND..1
(-1350 1775);
FORCEPROP 3 LASTPIN (-1350 1825) SIG_NAME GND\g
J 0
(-1340 1835);
DISPLAY 0.659574 (-1340 1835);
PAINT MONO (-1340 1835);
DISPLAY INVISIBLE (-1340 1835);
FORCEPROP 1 LAST VOLTAGE 0
J 0
(-1350 1775);
PAINT SKYBLUE (-1350 1775);
DISPLAY INVISIBLE (-1350 1775);
FORCEPROP 2 LAST BOM_COST MEM
J 0
(-1350 1780);
PAINT ORANGE (-1350 1780);
DISPLAY INVISIBLE (-1350 1780);
FORCEPROP 1 LAST SIZE 1B
J 0
(-1275 1725);
DISPLAY 1.787234 (-1275 1725);
PAINT GREEN (-1275 1725);
DISPLAY INVISIBLE (-1275 1725);
FORCEPROP 2 LAST CDS_LIB mstr_symbols
J 0
(-1350 1775);
PAINT ORANGE (-1350 1775);
DISPLAY INVISIBLE (-1350 1775);
FORCEPROP 1 LAST BODY_TYPE PLUMBING
J 0
(-1395 1732);
DISPLAY 0.340426 (-1395 1732);
PAINT GREEN (-1395 1732);
DISPLAY INVISIBLE (-1395 1732);
FORCEPROP 1 LAST PATH I180
J 0
(-1275 1775);
DISPLAY 0.872340 (-1275 1775);
PAINT AQUA (-1275 1775);
DISPLAY INVISIBLE (-1275 1775);
FORCEPROP 2 LAST ROOM DDR4_CH_B
J 0
(-1350 1780);
PAINT ORANGE (-1350 1780);
DISPLAY INVISIBLE (-1350 1780);
FORCEPROP 1 LAST HDL_POWER GND
J 0
(-1350 1925);
DISPLAY 1.404255 (-1350 1925);
PAINT GREEN (-1350 1925);
DISPLAY INVISIBLE (-1350 1925);
FORCEADD P12V_NVDIMM_DEF..1
(4100 2625);
FORCEPROP 3 LASTPIN (4100 2575) SIG_NAME P12V_NVDIMM_DEF\g
J 0
(4110 2585);
DISPLAY 0.659574 (4110 2585);
PAINT MONO (4110 2585);
DISPLAY INVISIBLE (4110 2585);
FORCEPROP 1 LAST VOLTAGE 12.0
J 0
(4055 2582);
DISPLAY 0.340426 (4055 2582);
PAINT SKYBLUE (4055 2582);
DISPLAY INVISIBLE (4055 2582);
FORCEPROP 2 LAST CDS_LIB mstr_symbols
J 0
(4100 2625);
PAINT ORANGE (4100 2625);
DISPLAY INVISIBLE (4100 2625);
FORCEPROP 1 LAST BODY_TYPE PLUMBING
J 0
(4055 2582);
DISPLAY 0.340426 (4055 2582);
PAINT GREEN (4055 2582);
DISPLAY INVISIBLE (4055 2582);
FORCEPROP 1 LAST PATH I181
J 0
(4150 2650);
DISPLAY 0.872340 (4150 2650);
PAINT AQUA (4150 2650);
DISPLAY INVISIBLE (4150 2650);
FORCEPROP 1 LAST HDL_POWER P12V_NVDIMM_DEF
J 1
(4100 2675);
DISPLAY 0.872340 (4100 2675);
PAINT GREEN (4100 2675);
DISPLAY INVISIBLE (4100 2675);
FORCEADD OFFPAGE..3
(2250 4800);
FORCEPROP 2 LAST $XR1 49 
J 0
(2554 4800);
DISPLAY 0.638298 (2554 4800);
PAINT MONO (2554 4800);
FORCEPROP 2 LAST $XR0 26 
J 0
(2464 4800);
DISPLAY 0.638298 (2464 4800);
PAINT MONO (2464 4800);
FORCEPROP 2 LAST CDS_LIB mstr_standard
J 0
(2250 4800);
DISPLAY 0.787234 (2250 4800);
PAINT MONO (2250 4800);
DISPLAY INVISIBLE (2250 4800);
FORCEPROP 1 LAST OFFPAGE TRUE
J 0
(2575 4675);
DISPLAY 0.936170 (2575 4675);
PAINT GREEN (2575 4675);
DISPLAY INVISIBLE (2575 4675);
FORCEPROP 1 LAST COMMENT_BODY TRUE
J 0
(2200 4700);
DISPLAY 0.936170 (2200 4700);
PAINT GREEN (2200 4700);
DISPLAY INVISIBLE (2200 4700);
FORCEPROP 2 LAST PATH I19
J 0
(2575 4850);
DISPLAY 1.021277 (2575 4850);
PAINT ORANGE (2575 4850);
DISPLAY INVISIBLE (2575 4850);
FORCEADD OFFPAGE..3
(5100 4850);
FORCEPROP 2 LAST $XR1 49 
J 0
(5404 4850);
DISPLAY 0.638298 (5404 4850);
PAINT MONO (5404 4850);
FORCEPROP 2 LAST $XR0 26 
J 0
(5314 4850);
DISPLAY 0.638298 (5314 4850);
PAINT MONO (5314 4850);
FORCEPROP 2 LAST CDS_LIB mstr_standard
J 0
(5100 4850);
DISPLAY 0.787234 (5100 4850);
PAINT MONO (5100 4850);
DISPLAY INVISIBLE (5100 4850);
FORCEPROP 1 LAST OFFPAGE TRUE
J 0
(5425 4725);
DISPLAY 0.936170 (5425 4725);
PAINT GREEN (5425 4725);
DISPLAY INVISIBLE (5425 4725);
FORCEPROP 1 LAST COMMENT_BODY TRUE
J 0
(5050 4750);
DISPLAY 0.936170 (5050 4750);
PAINT GREEN (5050 4750);
DISPLAY INVISIBLE (5050 4750);
FORCEPROP 2 LAST PATH I2
J 0
(5425 4900);
DISPLAY 1.021277 (5425 4900);
PAINT ORANGE (5425 4900);
DISPLAY INVISIBLE (5425 4900);
FORCEADD TAP..6
R 2
(4350 3950);
FORCEPROP 3 LASTPIN (4300 3950) SIG_NAME M_D_DQS_DN<9>
J 0
(4310 3960);
DISPLAY 0.659574 (4310 3960);
PAINT MONO (4310 3960);
DISPLAY INVISIBLE (4310 3960);
FORCEPROP 1 LASTPIN (4300 3950) BN 9
J 2
(4350 3960);
DISPLAY 0.617021 (4350 3960);
PAINT PINK (4350 3960);
FORCEPROP 2 LAST CDS_LIB mstr_standard
J 0
(4350 3950);
DISPLAY 0.787234 (4350 3950);
PAINT MONO (4350 3950);
DISPLAY INVISIBLE (4350 3950);
FORCEPROP 1 LAST BODY_TYPE PLUMBING
J 2
(4350 3900);
DISPLAY 1.234043 (4350 3900);
PAINT GREEN (4350 3900);
DISPLAY INVISIBLE (4350 3900);
FORCEPROP 1 LAST HDL_TAP TRUE
J 2
(4025 3825);
DISPLAY 1.234043 (4025 3825);
PAINT GREEN (4025 3825);
DISPLAY INVISIBLE (4025 3825);
FORCEPROP 1 LAST PATH I20
J 2
(4352 3950);
DISPLAY 0.872340 (4352 3950);
PAINT GREEN (4352 3950);
DISPLAY INVISIBLE (4352 3950);
FORCEADD TAP..6
R 2
(4350 4050);
FORCEPROP 3 LASTPIN (4300 4050) SIG_NAME M_D_DQS_DN<10>
J 0
(4310 4060);
DISPLAY 0.659574 (4310 4060);
PAINT MONO (4310 4060);
DISPLAY INVISIBLE (4310 4060);
FORCEPROP 1 LASTPIN (4300 4050) BN 10
J 2
(4350 4060);
DISPLAY 0.617021 (4350 4060);
PAINT PINK (4350 4060);
FORCEPROP 2 LAST CDS_LIB mstr_standard
J 0
(4350 4050);
DISPLAY 0.787234 (4350 4050);
PAINT MONO (4350 4050);
DISPLAY INVISIBLE (4350 4050);
FORCEPROP 1 LAST BODY_TYPE PLUMBING
J 2
(4350 4000);
DISPLAY 1.234043 (4350 4000);
PAINT GREEN (4350 4000);
DISPLAY INVISIBLE (4350 4000);
FORCEPROP 1 LAST HDL_TAP TRUE
J 2
(4025 3925);
DISPLAY 1.234043 (4025 3925);
PAINT GREEN (4025 3925);
DISPLAY INVISIBLE (4025 3925);
FORCEPROP 1 LAST PATH I21
J 2
(4352 4050);
DISPLAY 0.872340 (4352 4050);
PAINT GREEN (4352 4050);
DISPLAY INVISIBLE (4352 4050);
FORCEADD TAP..6
R 2
(4350 3850);
FORCEPROP 3 LASTPIN (4300 3850) SIG_NAME M_D_DQS_DN<8>
J 0
(4310 3860);
DISPLAY 0.659574 (4310 3860);
PAINT MONO (4310 3860);
DISPLAY INVISIBLE (4310 3860);
FORCEPROP 1 LASTPIN (4300 3850) BN 8
J 2
(4350 3860);
DISPLAY 0.617021 (4350 3860);
PAINT PINK (4350 3860);
FORCEPROP 2 LAST CDS_LIB mstr_standard
J 0
(4350 3850);
DISPLAY 0.787234 (4350 3850);
PAINT MONO (4350 3850);
DISPLAY INVISIBLE (4350 3850);
FORCEPROP 1 LAST BODY_TYPE PLUMBING
J 2
(4350 3800);
DISPLAY 1.234043 (4350 3800);
PAINT GREEN (4350 3800);
DISPLAY INVISIBLE (4350 3800);
FORCEPROP 1 LAST HDL_TAP TRUE
J 2
(4025 3725);
DISPLAY 1.234043 (4025 3725);
PAINT GREEN (4025 3725);
DISPLAY INVISIBLE (4025 3725);
FORCEPROP 1 LAST PATH I22
J 2
(4352 3850);
DISPLAY 0.872340 (4352 3850);
PAINT GREEN (4352 3850);
DISPLAY INVISIBLE (4352 3850);
FORCEADD TAP..6
R 2
(4350 3750);
FORCEPROP 3 LASTPIN (4300 3750) SIG_NAME M_D_DQS_DN<7>
J 0
(4310 3760);
DISPLAY 0.659574 (4310 3760);
PAINT MONO (4310 3760);
DISPLAY INVISIBLE (4310 3760);
FORCEPROP 1 LASTPIN (4300 3750) BN 7
J 2
(4350 3760);
DISPLAY 0.617021 (4350 3760);
PAINT PINK (4350 3760);
FORCEPROP 2 LAST CDS_LIB mstr_standard
J 0
(4350 3750);
DISPLAY 0.787234 (4350 3750);
PAINT MONO (4350 3750);
DISPLAY INVISIBLE (4350 3750);
FORCEPROP 1 LAST BODY_TYPE PLUMBING
J 2
(4350 3700);
DISPLAY 1.234043 (4350 3700);
PAINT GREEN (4350 3700);
DISPLAY INVISIBLE (4350 3700);
FORCEPROP 1 LAST HDL_TAP TRUE
J 2
(4025 3625);
DISPLAY 1.234043 (4025 3625);
PAINT GREEN (4025 3625);
DISPLAY INVISIBLE (4025 3625);
FORCEPROP 1 LAST PATH I23
J 2
(4352 3750);
DISPLAY 0.872340 (4352 3750);
PAINT GREEN (4352 3750);
DISPLAY INVISIBLE (4352 3750);
FORCEADD TAP..6
R 2
(4350 3650);
FORCEPROP 3 LASTPIN (4300 3650) SIG_NAME M_D_DQS_DN<6>
J 0
(4310 3660);
DISPLAY 0.659574 (4310 3660);
PAINT MONO (4310 3660);
DISPLAY INVISIBLE (4310 3660);
FORCEPROP 1 LASTPIN (4300 3650) BN 6
J 2
(4350 3660);
DISPLAY 0.617021 (4350 3660);
PAINT PINK (4350 3660);
FORCEPROP 2 LAST CDS_LIB mstr_standard
J 0
(4350 3650);
DISPLAY 0.787234 (4350 3650);
PAINT MONO (4350 3650);
DISPLAY INVISIBLE (4350 3650);
FORCEPROP 1 LAST BODY_TYPE PLUMBING
J 2
(4350 3600);
DISPLAY 1.234043 (4350 3600);
PAINT GREEN (4350 3600);
DISPLAY INVISIBLE (4350 3600);
FORCEPROP 1 LAST HDL_TAP TRUE
J 2
(4025 3525);
DISPLAY 1.234043 (4025 3525);
PAINT GREEN (4025 3525);
DISPLAY INVISIBLE (4025 3525);
FORCEPROP 1 LAST PATH I24
J 2
(4352 3650);
DISPLAY 0.872340 (4352 3650);
PAINT GREEN (4352 3650);
DISPLAY INVISIBLE (4352 3650);
FORCEADD TAP..6
R 2
(4100 4000);
FORCEPROP 3 LASTPIN (4050 4000) SIG_NAME M_D_DQS_DP<9>
J 0
(4060 4010);
DISPLAY 0.659574 (4060 4010);
PAINT MONO (4060 4010);
DISPLAY INVISIBLE (4060 4010);
FORCEPROP 1 LASTPIN (4050 4000) BN 9
J 2
(4100 4010);
DISPLAY 0.617021 (4100 4010);
PAINT PINK (4100 4010);
FORCEPROP 2 LAST CDS_LIB mstr_standard
J 0
(4100 4000);
DISPLAY 0.787234 (4100 4000);
PAINT MONO (4100 4000);
DISPLAY INVISIBLE (4100 4000);
FORCEPROP 1 LAST BODY_TYPE PLUMBING
J 2
(4100 3950);
DISPLAY 1.234043 (4100 3950);
PAINT GREEN (4100 3950);
DISPLAY INVISIBLE (4100 3950);
FORCEPROP 1 LAST HDL_TAP TRUE
J 2
(3775 3875);
DISPLAY 1.234043 (3775 3875);
PAINT GREEN (3775 3875);
DISPLAY INVISIBLE (3775 3875);
FORCEPROP 1 LAST PATH I25
J 2
(4102 4000);
DISPLAY 0.872340 (4102 4000);
PAINT GREEN (4102 4000);
DISPLAY INVISIBLE (4102 4000);
FORCEADD TAP..6
R 2
(4100 3900);
FORCEPROP 3 LASTPIN (4050 3900) SIG_NAME M_D_DQS_DP<8>
J 0
(4060 3910);
DISPLAY 0.659574 (4060 3910);
PAINT MONO (4060 3910);
DISPLAY INVISIBLE (4060 3910);
FORCEPROP 1 LASTPIN (4050 3900) BN 8
J 2
(4100 3910);
DISPLAY 0.617021 (4100 3910);
PAINT PINK (4100 3910);
FORCEPROP 2 LAST CDS_LIB mstr_standard
J 0
(4100 3900);
DISPLAY 0.787234 (4100 3900);
PAINT MONO (4100 3900);
DISPLAY INVISIBLE (4100 3900);
FORCEPROP 1 LAST BODY_TYPE PLUMBING
J 2
(4100 3850);
DISPLAY 1.234043 (4100 3850);
PAINT GREEN (4100 3850);
DISPLAY INVISIBLE (4100 3850);
FORCEPROP 1 LAST HDL_TAP TRUE
J 2
(3775 3775);
DISPLAY 1.234043 (3775 3775);
PAINT GREEN (3775 3775);
DISPLAY INVISIBLE (3775 3775);
FORCEPROP 1 LAST PATH I26
J 2
(4102 3900);
DISPLAY 0.872340 (4102 3900);
PAINT GREEN (4102 3900);
DISPLAY INVISIBLE (4102 3900);
FORCEADD TAP..6
R 2
(4100 3700);
FORCEPROP 3 LASTPIN (4050 3700) SIG_NAME M_D_DQS_DP<6>
J 0
(4060 3710);
DISPLAY 0.659574 (4060 3710);
PAINT MONO (4060 3710);
DISPLAY INVISIBLE (4060 3710);
FORCEPROP 1 LASTPIN (4050 3700) BN 6
J 2
(4100 3710);
DISPLAY 0.617021 (4100 3710);
PAINT PINK (4100 3710);
FORCEPROP 2 LAST CDS_LIB mstr_standard
J 0
(4100 3700);
DISPLAY 0.787234 (4100 3700);
PAINT MONO (4100 3700);
DISPLAY INVISIBLE (4100 3700);
FORCEPROP 1 LAST BODY_TYPE PLUMBING
J 2
(4100 3650);
DISPLAY 1.234043 (4100 3650);
PAINT GREEN (4100 3650);
DISPLAY INVISIBLE (4100 3650);
FORCEPROP 1 LAST HDL_TAP TRUE
J 2
(3775 3575);
DISPLAY 1.234043 (3775 3575);
PAINT GREEN (3775 3575);
DISPLAY INVISIBLE (3775 3575);
FORCEPROP 1 LAST PATH I27
J 2
(4102 3700);
DISPLAY 0.872340 (4102 3700);
PAINT GREEN (4102 3700);
DISPLAY INVISIBLE (4102 3700);
FORCEADD TAP..6
R 2
(4100 3800);
FORCEPROP 3 LASTPIN (4050 3800) SIG_NAME M_D_DQS_DP<7>
J 0
(4060 3810);
DISPLAY 0.659574 (4060 3810);
PAINT MONO (4060 3810);
DISPLAY INVISIBLE (4060 3810);
FORCEPROP 1 LASTPIN (4050 3800) BN 7
J 2
(4100 3810);
DISPLAY 0.617021 (4100 3810);
PAINT PINK (4100 3810);
FORCEPROP 2 LAST CDS_LIB mstr_standard
J 0
(4100 3800);
DISPLAY 0.787234 (4100 3800);
PAINT MONO (4100 3800);
DISPLAY INVISIBLE (4100 3800);
FORCEPROP 1 LAST BODY_TYPE PLUMBING
J 2
(4100 3750);
DISPLAY 1.234043 (4100 3750);
PAINT GREEN (4100 3750);
DISPLAY INVISIBLE (4100 3750);
FORCEPROP 1 LAST HDL_TAP TRUE
J 2
(3775 3675);
DISPLAY 1.234043 (3775 3675);
PAINT GREEN (3775 3675);
DISPLAY INVISIBLE (3775 3675);
FORCEPROP 1 LAST PATH I28
J 2
(4102 3800);
DISPLAY 0.872340 (4102 3800);
PAINT GREEN (4102 3800);
DISPLAY INVISIBLE (4102 3800);
FORCEADD TAP..6
R 2
(4100 3600);
FORCEPROP 3 LASTPIN (4050 3600) SIG_NAME M_D_DQS_DP<5>
J 0
(4060 3610);
DISPLAY 0.659574 (4060 3610);
PAINT MONO (4060 3610);
DISPLAY INVISIBLE (4060 3610);
FORCEPROP 1 LASTPIN (4050 3600) BN 5
J 2
(4100 3610);
DISPLAY 0.617021 (4100 3610);
PAINT PINK (4100 3610);
FORCEPROP 2 LAST CDS_LIB mstr_standard
J 0
(4100 3600);
DISPLAY 0.787234 (4100 3600);
PAINT MONO (4100 3600);
DISPLAY INVISIBLE (4100 3600);
FORCEPROP 1 LAST BODY_TYPE PLUMBING
J 2
(4100 3550);
DISPLAY 1.234043 (4100 3550);
PAINT GREEN (4100 3550);
DISPLAY INVISIBLE (4100 3550);
FORCEPROP 1 LAST HDL_TAP TRUE
J 2
(3775 3475);
DISPLAY 1.234043 (3775 3475);
PAINT GREEN (3775 3475);
DISPLAY INVISIBLE (3775 3475);
FORCEPROP 1 LAST PATH I29
J 2
(4102 3600);
DISPLAY 0.872340 (4102 3600);
PAINT GREEN (4102 3600);
DISPLAY INVISIBLE (4102 3600);
FORCEADD OFFPAGE..3
(5100 4800);
FORCEPROP 2 LAST $XR1 49 
J 0
(5404 4800);
DISPLAY 0.638298 (5404 4800);
PAINT MONO (5404 4800);
FORCEPROP 2 LAST $XR0 26 
J 0
(5314 4800);
DISPLAY 0.638298 (5314 4800);
PAINT MONO (5314 4800);
FORCEPROP 2 LAST CDS_LIB mstr_standard
J 0
(5100 4800);
DISPLAY 0.787234 (5100 4800);
PAINT MONO (5100 4800);
DISPLAY INVISIBLE (5100 4800);
FORCEPROP 1 LAST OFFPAGE TRUE
J 0
(5425 4675);
DISPLAY 0.936170 (5425 4675);
PAINT GREEN (5425 4675);
DISPLAY INVISIBLE (5425 4675);
FORCEPROP 1 LAST COMMENT_BODY TRUE
J 0
(5050 4700);
DISPLAY 0.936170 (5050 4700);
PAINT GREEN (5050 4700);
DISPLAY INVISIBLE (5050 4700);
FORCEPROP 2 LAST PATH I3
J 0
(5425 4850);
DISPLAY 1.021277 (5425 4850);
PAINT ORANGE (5425 4850);
DISPLAY INVISIBLE (5425 4850);
FORCEADD TAP..6
R 2
(4350 3550);
FORCEPROP 3 LASTPIN (4300 3550) SIG_NAME M_D_DQS_DN<5>
J 0
(4310 3560);
DISPLAY 0.659574 (4310 3560);
PAINT MONO (4310 3560);
DISPLAY INVISIBLE (4310 3560);
FORCEPROP 1 LASTPIN (4300 3550) BN 5
J 2
(4350 3560);
DISPLAY 0.617021 (4350 3560);
PAINT PINK (4350 3560);
FORCEPROP 2 LAST CDS_LIB mstr_standard
J 0
(4350 3550);
DISPLAY 0.787234 (4350 3550);
PAINT MONO (4350 3550);
DISPLAY INVISIBLE (4350 3550);
FORCEPROP 1 LAST BODY_TYPE PLUMBING
J 2
(4350 3500);
DISPLAY 1.234043 (4350 3500);
PAINT GREEN (4350 3500);
DISPLAY INVISIBLE (4350 3500);
FORCEPROP 1 LAST HDL_TAP TRUE
J 2
(4025 3425);
DISPLAY 1.234043 (4025 3425);
PAINT GREEN (4025 3425);
DISPLAY INVISIBLE (4025 3425);
FORCEPROP 1 LAST PATH I30
J 2
(4352 3550);
DISPLAY 0.872340 (4352 3550);
PAINT GREEN (4352 3550);
DISPLAY INVISIBLE (4352 3550);
FORCEADD TAP..6
R 2
(4350 3450);
FORCEPROP 3 LASTPIN (4300 3450) SIG_NAME M_D_DQS_DN<4>
J 0
(4310 3460);
DISPLAY 0.659574 (4310 3460);
PAINT MONO (4310 3460);
DISPLAY INVISIBLE (4310 3460);
FORCEPROP 1 LASTPIN (4300 3450) BN 4
J 2
(4350 3460);
DISPLAY 0.617021 (4350 3460);
PAINT PINK (4350 3460);
FORCEPROP 2 LAST CDS_LIB mstr_standard
J 0
(4350 3450);
DISPLAY 0.787234 (4350 3450);
PAINT MONO (4350 3450);
DISPLAY INVISIBLE (4350 3450);
FORCEPROP 1 LAST BODY_TYPE PLUMBING
J 2
(4350 3400);
DISPLAY 1.234043 (4350 3400);
PAINT GREEN (4350 3400);
DISPLAY INVISIBLE (4350 3400);
FORCEPROP 1 LAST HDL_TAP TRUE
J 2
(4025 3325);
DISPLAY 1.234043 (4025 3325);
PAINT GREEN (4025 3325);
DISPLAY INVISIBLE (4025 3325);
FORCEPROP 1 LAST PATH I31
J 2
(4352 3450);
DISPLAY 0.872340 (4352 3450);
PAINT GREEN (4352 3450);
DISPLAY INVISIBLE (4352 3450);
FORCEADD TAP..6
R 2
(4350 3350);
FORCEPROP 3 LASTPIN (4300 3350) SIG_NAME M_D_DQS_DN<3>
J 0
(4310 3360);
DISPLAY 0.659574 (4310 3360);
PAINT MONO (4310 3360);
DISPLAY INVISIBLE (4310 3360);
FORCEPROP 1 LASTPIN (4300 3350) BN 3
J 2
(4350 3360);
DISPLAY 0.617021 (4350 3360);
PAINT PINK (4350 3360);
FORCEPROP 2 LAST CDS_LIB mstr_standard
J 0
(4350 3350);
DISPLAY 0.787234 (4350 3350);
PAINT MONO (4350 3350);
DISPLAY INVISIBLE (4350 3350);
FORCEPROP 1 LAST BODY_TYPE PLUMBING
J 2
(4350 3300);
DISPLAY 1.234043 (4350 3300);
PAINT GREEN (4350 3300);
DISPLAY INVISIBLE (4350 3300);
FORCEPROP 1 LAST HDL_TAP TRUE
J 2
(4025 3225);
DISPLAY 1.234043 (4025 3225);
PAINT GREEN (4025 3225);
DISPLAY INVISIBLE (4025 3225);
FORCEPROP 1 LAST PATH I32
J 2
(4352 3350);
DISPLAY 0.872340 (4352 3350);
PAINT GREEN (4352 3350);
DISPLAY INVISIBLE (4352 3350);
FORCEADD TAP..6
R 2
(4350 3250);
FORCEPROP 3 LASTPIN (4300 3250) SIG_NAME M_D_DQS_DN<2>
J 0
(4310 3260);
DISPLAY 0.659574 (4310 3260);
PAINT MONO (4310 3260);
DISPLAY INVISIBLE (4310 3260);
FORCEPROP 1 LASTPIN (4300 3250) BN 2
J 2
(4350 3260);
DISPLAY 0.617021 (4350 3260);
PAINT PINK (4350 3260);
FORCEPROP 2 LAST CDS_LIB mstr_standard
J 0
(4350 3250);
DISPLAY 0.787234 (4350 3250);
PAINT MONO (4350 3250);
DISPLAY INVISIBLE (4350 3250);
FORCEPROP 1 LAST BODY_TYPE PLUMBING
J 2
(4350 3200);
DISPLAY 1.234043 (4350 3200);
PAINT GREEN (4350 3200);
DISPLAY INVISIBLE (4350 3200);
FORCEPROP 1 LAST HDL_TAP TRUE
J 2
(4025 3125);
DISPLAY 1.234043 (4025 3125);
PAINT GREEN (4025 3125);
DISPLAY INVISIBLE (4025 3125);
FORCEPROP 1 LAST PATH I33
J 2
(4352 3250);
DISPLAY 0.872340 (4352 3250);
PAINT GREEN (4352 3250);
DISPLAY INVISIBLE (4352 3250);
FORCEADD TAP..6
R 2
(4350 3050);
FORCEPROP 3 LASTPIN (4300 3050) SIG_NAME M_D_DQS_DN<0>
J 0
(4310 3060);
DISPLAY 0.659574 (4310 3060);
PAINT MONO (4310 3060);
DISPLAY INVISIBLE (4310 3060);
FORCEPROP 1 LASTPIN (4300 3050) BN 0
J 2
(4350 3060);
DISPLAY 0.617021 (4350 3060);
PAINT PINK (4350 3060);
FORCEPROP 2 LAST CDS_LIB mstr_standard
J 0
(4350 3050);
DISPLAY 0.787234 (4350 3050);
PAINT MONO (4350 3050);
DISPLAY INVISIBLE (4350 3050);
FORCEPROP 1 LAST BODY_TYPE PLUMBING
J 2
(4350 3000);
DISPLAY 1.234043 (4350 3000);
PAINT GREEN (4350 3000);
DISPLAY INVISIBLE (4350 3000);
FORCEPROP 1 LAST HDL_TAP TRUE
J 2
(4025 2925);
DISPLAY 1.234043 (4025 2925);
PAINT GREEN (4025 2925);
DISPLAY INVISIBLE (4025 2925);
FORCEPROP 1 LAST PATH I34
J 2
(4352 3050);
DISPLAY 0.872340 (4352 3050);
PAINT GREEN (4352 3050);
DISPLAY INVISIBLE (4352 3050);
FORCEADD TAP..6
R 2
(4350 3150);
FORCEPROP 3 LASTPIN (4300 3150) SIG_NAME M_D_DQS_DN<1>
J 0
(4310 3160);
DISPLAY 0.659574 (4310 3160);
PAINT MONO (4310 3160);
DISPLAY INVISIBLE (4310 3160);
FORCEPROP 1 LASTPIN (4300 3150) BN 1
J 2
(4350 3160);
DISPLAY 0.617021 (4350 3160);
PAINT PINK (4350 3160);
FORCEPROP 2 LAST CDS_LIB mstr_standard
J 0
(4350 3150);
DISPLAY 0.787234 (4350 3150);
PAINT MONO (4350 3150);
DISPLAY INVISIBLE (4350 3150);
FORCEPROP 1 LAST BODY_TYPE PLUMBING
J 2
(4350 3100);
DISPLAY 1.234043 (4350 3100);
PAINT GREEN (4350 3100);
DISPLAY INVISIBLE (4350 3100);
FORCEPROP 1 LAST HDL_TAP TRUE
J 2
(4025 3025);
DISPLAY 1.234043 (4025 3025);
PAINT GREEN (4025 3025);
DISPLAY INVISIBLE (4025 3025);
FORCEPROP 1 LAST PATH I35
J 2
(4352 3150);
DISPLAY 0.872340 (4352 3150);
PAINT GREEN (4352 3150);
DISPLAY INVISIBLE (4352 3150);
FORCEADD TAP..6
R 2
(4100 3500);
FORCEPROP 3 LASTPIN (4050 3500) SIG_NAME M_D_DQS_DP<4>
J 0
(4060 3510);
DISPLAY 0.659574 (4060 3510);
PAINT MONO (4060 3510);
DISPLAY INVISIBLE (4060 3510);
FORCEPROP 1 LASTPIN (4050 3500) BN 4
J 2
(4100 3510);
DISPLAY 0.617021 (4100 3510);
PAINT PINK (4100 3510);
FORCEPROP 2 LAST CDS_LIB mstr_standard
J 0
(4100 3500);
DISPLAY 0.787234 (4100 3500);
PAINT MONO (4100 3500);
DISPLAY INVISIBLE (4100 3500);
FORCEPROP 1 LAST BODY_TYPE PLUMBING
J 2
(4100 3450);
DISPLAY 1.234043 (4100 3450);
PAINT GREEN (4100 3450);
DISPLAY INVISIBLE (4100 3450);
FORCEPROP 1 LAST HDL_TAP TRUE
J 2
(3775 3375);
DISPLAY 1.234043 (3775 3375);
PAINT GREEN (3775 3375);
DISPLAY INVISIBLE (3775 3375);
FORCEPROP 1 LAST PATH I36
J 2
(4102 3500);
DISPLAY 0.872340 (4102 3500);
PAINT GREEN (4102 3500);
DISPLAY INVISIBLE (4102 3500);
FORCEADD TAP..6
R 2
(4100 3400);
FORCEPROP 3 LASTPIN (4050 3400) SIG_NAME M_D_DQS_DP<3>
J 0
(4060 3410);
DISPLAY 0.659574 (4060 3410);
PAINT MONO (4060 3410);
DISPLAY INVISIBLE (4060 3410);
FORCEPROP 1 LASTPIN (4050 3400) BN 3
J 2
(4100 3410);
DISPLAY 0.617021 (4100 3410);
PAINT PINK (4100 3410);
FORCEPROP 2 LAST CDS_LIB mstr_standard
J 0
(4100 3400);
DISPLAY 0.787234 (4100 3400);
PAINT MONO (4100 3400);
DISPLAY INVISIBLE (4100 3400);
FORCEPROP 1 LAST BODY_TYPE PLUMBING
J 2
(4100 3350);
DISPLAY 1.234043 (4100 3350);
PAINT GREEN (4100 3350);
DISPLAY INVISIBLE (4100 3350);
FORCEPROP 1 LAST HDL_TAP TRUE
J 2
(3775 3275);
DISPLAY 1.234043 (3775 3275);
PAINT GREEN (3775 3275);
DISPLAY INVISIBLE (3775 3275);
FORCEPROP 1 LAST PATH I37
J 2
(4102 3400);
DISPLAY 0.872340 (4102 3400);
PAINT GREEN (4102 3400);
DISPLAY INVISIBLE (4102 3400);
FORCEADD TAP..6
R 2
(4100 3300);
FORCEPROP 3 LASTPIN (4050 3300) SIG_NAME M_D_DQS_DP<2>
J 0
(4060 3310);
DISPLAY 0.659574 (4060 3310);
PAINT MONO (4060 3310);
DISPLAY INVISIBLE (4060 3310);
FORCEPROP 1 LASTPIN (4050 3300) BN 2
J 2
(4100 3310);
DISPLAY 0.617021 (4100 3310);
PAINT PINK (4100 3310);
FORCEPROP 2 LAST CDS_LIB mstr_standard
J 0
(4100 3300);
DISPLAY 0.787234 (4100 3300);
PAINT MONO (4100 3300);
DISPLAY INVISIBLE (4100 3300);
FORCEPROP 1 LAST BODY_TYPE PLUMBING
J 2
(4100 3250);
DISPLAY 1.234043 (4100 3250);
PAINT GREEN (4100 3250);
DISPLAY INVISIBLE (4100 3250);
FORCEPROP 1 LAST HDL_TAP TRUE
J 2
(3775 3175);
DISPLAY 1.234043 (3775 3175);
PAINT GREEN (3775 3175);
DISPLAY INVISIBLE (3775 3175);
FORCEPROP 1 LAST PATH I38
J 2
(4102 3300);
DISPLAY 0.872340 (4102 3300);
PAINT GREEN (4102 3300);
DISPLAY INVISIBLE (4102 3300);
FORCEADD TAP..6
R 2
(4100 3200);
FORCEPROP 3 LASTPIN (4050 3200) SIG_NAME M_D_DQS_DP<1>
J 0
(4060 3210);
DISPLAY 0.659574 (4060 3210);
PAINT MONO (4060 3210);
DISPLAY INVISIBLE (4060 3210);
FORCEPROP 1 LASTPIN (4050 3200) BN 1
J 2
(4100 3210);
DISPLAY 0.617021 (4100 3210);
PAINT PINK (4100 3210);
FORCEPROP 2 LAST CDS_LIB mstr_standard
J 0
(4100 3200);
DISPLAY 0.787234 (4100 3200);
PAINT MONO (4100 3200);
DISPLAY INVISIBLE (4100 3200);
FORCEPROP 1 LAST BODY_TYPE PLUMBING
J 2
(4100 3150);
DISPLAY 1.234043 (4100 3150);
PAINT GREEN (4100 3150);
DISPLAY INVISIBLE (4100 3150);
FORCEPROP 1 LAST HDL_TAP TRUE
J 2
(3775 3075);
DISPLAY 1.234043 (3775 3075);
PAINT GREEN (3775 3075);
DISPLAY INVISIBLE (3775 3075);
FORCEPROP 1 LAST PATH I39
J 2
(4102 3200);
DISPLAY 0.872340 (4102 3200);
PAINT GREEN (4102 3200);
DISPLAY INVISIBLE (4102 3200);
FORCEADD TAP..6
R 2
(4350 4750);
FORCEPROP 3 LASTPIN (4300 4750) SIG_NAME M_D_DQS_DN<17>
J 0
(4310 4760);
DISPLAY 0.659574 (4310 4760);
PAINT MONO (4310 4760);
DISPLAY INVISIBLE (4310 4760);
FORCEPROP 1 LASTPIN (4300 4750) BN 17
J 2
(4350 4760);
DISPLAY 0.617021 (4350 4760);
PAINT PINK (4350 4760);
FORCEPROP 2 LAST CDS_LIB mstr_standard
J 2
(4350 4750);
DISPLAY 0.787234 (4350 4750);
PAINT MONO (4350 4750);
DISPLAY INVISIBLE (4350 4750);
FORCEPROP 1 LAST BODY_TYPE PLUMBING
J 2
(4350 4700);
DISPLAY 1.234043 (4350 4700);
PAINT GREEN (4350 4700);
DISPLAY INVISIBLE (4350 4700);
FORCEPROP 1 LAST HDL_TAP TRUE
J 2
(4025 4625);
DISPLAY 1.234043 (4025 4625);
PAINT GREEN (4025 4625);
DISPLAY INVISIBLE (4025 4625);
FORCEPROP 1 LAST PATH I4
J 2
(4352 4750);
DISPLAY 0.872340 (4352 4750);
PAINT GREEN (4352 4750);
DISPLAY INVISIBLE (4352 4750);
FORCEADD TAP..6
R 2
(4100 3100);
FORCEPROP 3 LASTPIN (4050 3100) SIG_NAME M_D_DQS_DP<0>
J 0
(4060 3110);
DISPLAY 0.659574 (4060 3110);
PAINT MONO (4060 3110);
DISPLAY INVISIBLE (4060 3110);
FORCEPROP 1 LASTPIN (4050 3100) BN 0
J 2
(4100 3110);
DISPLAY 0.617021 (4100 3110);
PAINT PINK (4100 3110);
FORCEPROP 2 LAST CDS_LIB mstr_standard
J 0
(4100 3100);
DISPLAY 0.787234 (4100 3100);
PAINT MONO (4100 3100);
DISPLAY INVISIBLE (4100 3100);
FORCEPROP 1 LAST BODY_TYPE PLUMBING
J 2
(4100 3050);
DISPLAY 1.234043 (4100 3050);
PAINT GREEN (4100 3050);
DISPLAY INVISIBLE (4100 3050);
FORCEPROP 1 LAST HDL_TAP TRUE
J 2
(3775 2975);
DISPLAY 1.234043 (3775 2975);
PAINT GREEN (3775 2975);
DISPLAY INVISIBLE (3775 2975);
FORCEPROP 1 LAST PATH I40
J 2
(4102 3100);
DISPLAY 0.872340 (4102 3100);
PAINT GREEN (4102 3100);
DISPLAY INVISIBLE (4102 3100);
FORCEADD SCONN288_H44441003..3
(5250 2050);
FORCEPROP 1 LAST LOCATION J6M1
J 0
(4800 3450);
DISPLAY 0.617021 (4800 3450);
PAINT AQUA (4800 3450);
FORCEPROP 1 LAST PART_NUMBER H44441-003
J 0
(4800 700);
DISPLAY 0.617021 (4800 700);
PAINT BLUE (4800 700);
FORCEPROP 1 LAST MATERIAL SCONN
J 0
(4800 3400);
DISPLAY 0.617021 (4800 3400);
PAINT SKYBLUE (4800 3400);
FORCEPROP 2 LASTPIN (4750 3200) $PN 2
J 2
(4740 3210);
DISPLAY 0.617021 (4740 3210);
PAINT ORANGE (4740 3210);
FORCEPROP 2 LASTPIN (4750 3150) $PN 4
J 2
(4740 3160);
DISPLAY 0.617021 (4740 3160);
PAINT ORANGE (4740 3160);
FORCEPROP 2 LASTPIN (4750 3100) $PN 6
J 2
(4740 3110);
DISPLAY 0.617021 (4740 3110);
PAINT ORANGE (4740 3110);
FORCEPROP 2 LASTPIN (4750 3050) $PN 9
J 2
(4740 3060);
DISPLAY 0.617021 (4740 3060);
PAINT ORANGE (4740 3060);
FORCEPROP 2 LASTPIN (4750 3000) $PN 11
J 2
(4740 3010);
DISPLAY 0.617021 (4740 3010);
PAINT ORANGE (4740 3010);
FORCEPROP 2 LASTPIN (4750 2950) $PN 13
J 2
(4740 2960);
DISPLAY 0.617021 (4740 2960);
PAINT ORANGE (4740 2960);
FORCEPROP 2 LASTPIN (4750 2900) $PN 15
J 2
(4740 2910);
DISPLAY 0.617021 (4740 2910);
PAINT ORANGE (4740 2910);
FORCEPROP 2 LASTPIN (4750 2850) $PN 17
J 2
(4740 2860);
DISPLAY 0.617021 (4740 2860);
PAINT ORANGE (4740 2860);
FORCEPROP 2 LASTPIN (4750 2800) $PN 20
J 2
(4740 2810);
DISPLAY 0.617021 (4740 2810);
PAINT ORANGE (4740 2810);
FORCEPROP 2 LASTPIN (4750 2750) $PN 22
J 2
(4740 2760);
DISPLAY 0.617021 (4740 2760);
PAINT ORANGE (4740 2760);
FORCEPROP 2 LASTPIN (4750 2700) $PN 24
J 2
(4740 2710);
DISPLAY 0.617021 (4740 2710);
PAINT ORANGE (4740 2710);
FORCEPROP 2 LASTPIN (4750 2650) $PN 26
J 2
(4740 2660);
DISPLAY 0.617021 (4740 2660);
PAINT ORANGE (4740 2660);
FORCEPROP 2 LASTPIN (4750 2600) $PN 28
J 2
(4740 2610);
DISPLAY 0.617021 (4740 2610);
PAINT ORANGE (4740 2610);
FORCEPROP 2 LASTPIN (4750 2550) $PN 31
J 2
(4740 2560);
DISPLAY 0.617021 (4740 2560);
PAINT ORANGE (4740 2560);
FORCEPROP 2 LASTPIN (4750 2500) $PN 33
J 2
(4740 2510);
DISPLAY 0.617021 (4740 2510);
PAINT ORANGE (4740 2510);
FORCEPROP 2 LASTPIN (4750 2450) $PN 35
J 2
(4740 2460);
DISPLAY 0.617021 (4740 2460);
PAINT ORANGE (4740 2460);
FORCEPROP 2 LASTPIN (4750 2400) $PN 37
J 2
(4740 2410);
DISPLAY 0.617021 (4740 2410);
PAINT ORANGE (4740 2410);
FORCEPROP 2 LASTPIN (4750 2350) $PN 39
J 2
(4740 2360);
DISPLAY 0.617021 (4740 2360);
PAINT ORANGE (4740 2360);
FORCEPROP 2 LASTPIN (4750 2300) $PN 42
J 2
(4740 2310);
DISPLAY 0.617021 (4740 2310);
PAINT ORANGE (4740 2310);
FORCEPROP 2 LASTPIN (4750 2200) $PN 46
J 2
(4740 2210);
DISPLAY 0.617021 (4740 2210);
PAINT ORANGE (4740 2210);
FORCEPROP 2 LASTPIN (4750 2150) $PN 48
J 2
(4740 2160);
DISPLAY 0.617021 (4740 2160);
PAINT ORANGE (4740 2160);
FORCEPROP 2 LASTPIN (4750 2100) $PN 50
J 2
(4740 2110);
DISPLAY 0.617021 (4740 2110);
PAINT ORANGE (4740 2110);
FORCEPROP 2 LASTPIN (4750 2050) $PN 53
J 2
(4740 2060);
DISPLAY 0.617021 (4740 2060);
PAINT ORANGE (4740 2060);
FORCEPROP 2 LASTPIN (4750 2000) $PN 55
J 2
(4740 2010);
DISPLAY 0.617021 (4740 2010);
PAINT ORANGE (4740 2010);
FORCEPROP 2 LASTPIN (4750 1950) $PN 57
J 2
(4740 1960);
DISPLAY 0.617021 (4740 1960);
PAINT ORANGE (4740 1960);
FORCEPROP 2 LASTPIN (4750 1900) $PN 94
J 2
(4740 1910);
DISPLAY 0.617021 (4740 1910);
PAINT ORANGE (4740 1910);
FORCEPROP 2 LASTPIN (4750 1850) $PN 96
J 2
(4740 1860);
DISPLAY 0.617021 (4740 1860);
PAINT ORANGE (4740 1860);
FORCEPROP 2 LASTPIN (4750 1800) $PN 98
J 2
(4740 1810);
DISPLAY 0.617021 (4740 1810);
PAINT ORANGE (4740 1810);
FORCEPROP 2 LASTPIN (4750 1750) $PN 101
J 2
(4740 1760);
DISPLAY 0.617021 (4740 1760);
PAINT ORANGE (4740 1760);
FORCEPROP 2 LASTPIN (4750 1700) $PN 103
J 2
(4740 1710);
DISPLAY 0.617021 (4740 1710);
PAINT ORANGE (4740 1710);
FORCEPROP 2 LASTPIN (4750 1600) $PN 107
J 2
(4740 1610);
DISPLAY 0.617021 (4740 1610);
PAINT ORANGE (4740 1610);
FORCEPROP 2 LASTPIN (4750 1500) $PN 112
J 2
(4740 1510);
DISPLAY 0.617021 (4740 1510);
PAINT ORANGE (4740 1510);
FORCEPROP 2 LASTPIN (4750 1450) $PN 114
J 2
(4740 1460);
DISPLAY 0.617021 (4740 1460);
PAINT ORANGE (4740 1460);
FORCEPROP 2 LASTPIN (4750 1400) $PN 116
J 2
(4740 1410);
DISPLAY 0.617021 (4740 1410);
PAINT ORANGE (4740 1410);
FORCEPROP 2 LASTPIN (4750 1350) $PN 118
J 2
(4740 1360);
DISPLAY 0.617021 (4740 1360);
PAINT ORANGE (4740 1360);
FORCEPROP 2 LASTPIN (4750 1300) $PN 120
J 2
(4740 1310);
DISPLAY 0.617021 (4740 1310);
PAINT ORANGE (4740 1310);
FORCEPROP 2 LASTPIN (4750 1250) $PN 123
J 2
(4740 1260);
DISPLAY 0.617021 (4740 1260);
PAINT ORANGE (4740 1260);
FORCEPROP 2 LASTPIN (4750 1200) $PN 125
J 2
(4740 1210);
DISPLAY 0.617021 (4740 1210);
PAINT ORANGE (4740 1210);
FORCEPROP 2 LASTPIN (4750 1150) $PN 127
J 2
(4740 1160);
DISPLAY 0.617021 (4740 1160);
PAINT ORANGE (4740 1160);
FORCEPROP 2 LASTPIN (4750 1100) $PN 129
J 2
(4740 1110);
DISPLAY 0.617021 (4740 1110);
PAINT ORANGE (4740 1110);
FORCEPROP 2 LASTPIN (4750 1050) $PN 131
J 2
(4740 1060);
DISPLAY 0.617021 (4740 1060);
PAINT ORANGE (4740 1060);
FORCEPROP 2 LASTPIN (4750 1000) $PN 134
J 2
(4740 1010);
DISPLAY 0.617021 (4740 1010);
PAINT ORANGE (4740 1010);
FORCEPROP 2 LASTPIN (4750 950) $PN 136
J 2
(4740 960);
DISPLAY 0.617021 (4740 960);
PAINT ORANGE (4740 960);
FORCEPROP 2 LASTPIN (4750 900) $PN 138
J 2
(4740 910);
DISPLAY 0.617021 (4740 910);
PAINT ORANGE (4740 910);
FORCEPROP 2 LASTPIN (5750 3200) $PN 147
J 0
(5760 3210);
DISPLAY 0.617021 (5760 3210);
PAINT ORANGE (5760 3210);
FORCEPROP 2 LASTPIN (5750 3150) $PN 149
J 0
(5760 3160);
DISPLAY 0.617021 (5760 3160);
PAINT ORANGE (5760 3160);
FORCEPROP 2 LASTPIN (5750 3100) $PN 151
J 0
(5760 3110);
DISPLAY 0.617021 (5760 3110);
PAINT ORANGE (5760 3110);
FORCEPROP 2 LASTPIN (5750 3050) $PN 154
J 0
(5760 3060);
DISPLAY 0.617021 (5760 3060);
PAINT ORANGE (5760 3060);
FORCEPROP 2 LASTPIN (5750 3000) $PN 156
J 0
(5760 3010);
DISPLAY 0.617021 (5760 3010);
PAINT ORANGE (5760 3010);
FORCEPROP 2 LASTPIN (5750 2950) $PN 158
J 0
(5760 2960);
DISPLAY 0.617021 (5760 2960);
PAINT ORANGE (5760 2960);
FORCEPROP 2 LASTPIN (5750 2900) $PN 160
J 0
(5760 2910);
DISPLAY 0.617021 (5760 2910);
PAINT ORANGE (5760 2910);
FORCEPROP 2 LASTPIN (5750 2850) $PN 162
J 0
(5760 2860);
DISPLAY 0.617021 (5760 2860);
PAINT ORANGE (5760 2860);
FORCEPROP 2 LASTPIN (5750 2800) $PN 165
J 0
(5760 2810);
DISPLAY 0.617021 (5760 2810);
PAINT ORANGE (5760 2810);
FORCEPROP 2 LASTPIN (5750 2750) $PN 167
J 0
(5760 2760);
DISPLAY 0.617021 (5760 2760);
PAINT ORANGE (5760 2760);
FORCEPROP 2 LASTPIN (5750 2700) $PN 169
J 0
(5760 2710);
DISPLAY 0.617021 (5760 2710);
PAINT ORANGE (5760 2710);
FORCEPROP 2 LASTPIN (5750 2650) $PN 171
J 0
(5760 2660);
DISPLAY 0.617021 (5760 2660);
PAINT ORANGE (5760 2660);
FORCEPROP 2 LASTPIN (5750 2600) $PN 173
J 0
(5760 2610);
DISPLAY 0.617021 (5760 2610);
PAINT ORANGE (5760 2610);
FORCEPROP 2 LASTPIN (5750 2550) $PN 176
J 0
(5760 2560);
DISPLAY 0.617021 (5760 2560);
PAINT ORANGE (5760 2560);
FORCEPROP 2 LASTPIN (5750 2500) $PN 178
J 0
(5760 2510);
DISPLAY 0.617021 (5760 2510);
PAINT ORANGE (5760 2510);
FORCEPROP 2 LASTPIN (5750 2450) $PN 180
J 0
(5760 2460);
DISPLAY 0.617021 (5760 2460);
PAINT ORANGE (5760 2460);
FORCEPROP 2 LASTPIN (5750 2400) $PN 182
J 0
(5760 2410);
DISPLAY 0.617021 (5760 2410);
PAINT ORANGE (5760 2410);
FORCEPROP 2 LASTPIN (5750 2300) $PN 187
J 0
(5760 2310);
DISPLAY 0.617021 (5760 2310);
PAINT ORANGE (5760 2310);
FORCEPROP 2 LASTPIN (5750 2250) $PN 189
J 0
(5760 2260);
DISPLAY 0.617021 (5760 2260);
PAINT ORANGE (5760 2260);
FORCEPROP 2 LASTPIN (5750 2200) $PN 191
J 0
(5760 2210);
DISPLAY 0.617021 (5760 2210);
PAINT ORANGE (5760 2210);
FORCEPROP 2 LASTPIN (5750 2150) $PN 193
J 0
(5760 2160);
DISPLAY 0.617021 (5760 2160);
PAINT ORANGE (5760 2160);
FORCEPROP 2 LASTPIN (5750 2100) $PN 195
J 0
(5760 2110);
DISPLAY 0.617021 (5760 2110);
PAINT ORANGE (5760 2110);
FORCEPROP 2 LASTPIN (5750 2050) $PN 198
J 0
(5760 2060);
DISPLAY 0.617021 (5760 2060);
PAINT ORANGE (5760 2060);
FORCEPROP 2 LASTPIN (5750 2000) $PN 200
J 0
(5760 2010);
DISPLAY 0.617021 (5760 2010);
PAINT ORANGE (5760 2010);
FORCEPROP 2 LASTPIN (5750 1950) $PN 202
J 0
(5760 1960);
DISPLAY 0.617021 (5760 1960);
PAINT ORANGE (5760 1960);
FORCEPROP 2 LASTPIN (5750 1850) $PN 241
J 0
(5760 1860);
DISPLAY 0.617021 (5760 1860);
PAINT ORANGE (5760 1860);
FORCEPROP 2 LASTPIN (5750 1800) $PN 243
J 0
(5760 1810);
DISPLAY 0.617021 (5760 1810);
PAINT ORANGE (5760 1810);
FORCEPROP 2 LASTPIN (5750 1750) $PN 246
J 0
(5760 1760);
DISPLAY 0.617021 (5760 1760);
PAINT ORANGE (5760 1760);
FORCEPROP 2 LASTPIN (5750 1700) $PN 248
J 0
(5760 1710);
DISPLAY 0.617021 (5760 1710);
PAINT ORANGE (5760 1710);
FORCEPROP 2 LASTPIN (5750 1650) $PN 250
J 0
(5760 1660);
DISPLAY 0.617021 (5760 1660);
PAINT ORANGE (5760 1660);
FORCEPROP 2 LASTPIN (5750 1600) $PN 252
J 0
(5760 1610);
DISPLAY 0.617021 (5760 1610);
PAINT ORANGE (5760 1610);
FORCEPROP 2 LASTPIN (5750 1550) $PN 254
J 0
(5760 1560);
DISPLAY 0.617021 (5760 1560);
PAINT ORANGE (5760 1560);
FORCEPROP 2 LASTPIN (5750 1500) $PN 257
J 0
(5760 1510);
DISPLAY 0.617021 (5760 1510);
PAINT ORANGE (5760 1510);
FORCEPROP 2 LASTPIN (5750 1450) $PN 259
J 0
(5760 1460);
DISPLAY 0.617021 (5760 1460);
PAINT ORANGE (5760 1460);
FORCEPROP 2 LASTPIN (5750 1400) $PN 261
J 0
(5760 1410);
DISPLAY 0.617021 (5760 1410);
PAINT ORANGE (5760 1410);
FORCEPROP 2 LASTPIN (5750 1350) $PN 263
J 0
(5760 1360);
DISPLAY 0.617021 (5760 1360);
PAINT ORANGE (5760 1360);
FORCEPROP 2 LASTPIN (5750 1300) $PN 265
J 0
(5760 1310);
DISPLAY 0.617021 (5760 1310);
PAINT ORANGE (5760 1310);
FORCEPROP 2 LASTPIN (5750 1250) $PN 268
J 0
(5760 1260);
DISPLAY 0.617021 (5760 1260);
PAINT ORANGE (5760 1260);
FORCEPROP 2 LASTPIN (5750 1200) $PN 270
J 0
(5760 1210);
DISPLAY 0.617021 (5760 1210);
PAINT ORANGE (5760 1210);
FORCEPROP 2 LASTPIN (5750 1150) $PN 272
J 0
(5760 1160);
DISPLAY 0.617021 (5760 1160);
PAINT ORANGE (5760 1160);
FORCEPROP 2 LASTPIN (5750 1100) $PN 274
J 0
(5760 1110);
DISPLAY 0.617021 (5760 1110);
PAINT ORANGE (5760 1110);
FORCEPROP 2 LASTPIN (5750 1050) $PN 276
J 0
(5760 1060);
DISPLAY 0.617021 (5760 1060);
PAINT ORANGE (5760 1060);
FORCEPROP 2 LASTPIN (5750 1000) $PN 279
J 0
(5760 1010);
DISPLAY 0.617021 (5760 1010);
PAINT ORANGE (5760 1010);
FORCEPROP 2 LASTPIN (5750 950) $PN 281
J 0
(5760 960);
DISPLAY 0.617021 (5760 960);
PAINT ORANGE (5760 960);
FORCEPROP 2 LASTPIN (5750 900) $PN 283
J 0
(5760 910);
DISPLAY 0.617021 (5760 910);
PAINT ORANGE (5760 910);
FORCEPROP 2 LASTPIN (5750 2350) $PN 184
J 0
(5760 2360);
DISPLAY 0.617021 (5760 2360);
PAINT ORANGE (5760 2360);
FORCEPROP 2 LASTPIN (4750 2250) $PN 44
J 2
(4740 2260);
DISPLAY 0.617021 (4740 2260);
PAINT ORANGE (4740 2260);
FORCEPROP 2 LASTPIN (4750 1650) $PN 105
J 2
(4740 1660);
DISPLAY 0.617021 (4740 1660);
PAINT ORANGE (4740 1660);
FORCEPROP 2 LASTPIN (4750 1550) $PN 109
J 2
(4740 1560);
DISPLAY 0.617021 (4740 1560);
PAINT ORANGE (4740 1560);
FORCEPROP 2 LASTPIN (5750 1900) $PN 239
J 0
(5760 1910);
DISPLAY 0.617021 (5760 1910);
PAINT ORANGE (5760 1910);
FORCEPROP 0 LAST BOM_SS NOPOP
J 0
(5060 3517);
DISPLAY 1.021277 (5060 3517);
PAINT BROWN (5060 3517);
DISPLAY BOTH (5060 3517);
FORCEPROP 1 LAST PACK_TYPE PIP
J 0
(4800 3500);
PAINT SKYBLUE (4800 3500);
DISPLAY INVISIBLE (4800 3500);
FORCEPROP 2 LAST BOM_COST MEM
J 0
(5250 2050);
PAINT ORANGE (5250 2050);
DISPLAY INVISIBLE (5250 2050);
FORCEPROP 2 LAST CDS_LIB mstr_sconn
J 0
(5250 2050);
PAINT ORANGE (5250 2050);
DISPLAY INVISIBLE (5250 2050);
FORCEPROP 2 LAST SEC_TYPE PIP
J 0
(4800 3500);
DISPLAY 1.021277 (4800 3500);
PAINT ORANGE (4800 3500);
DISPLAY INVISIBLE (4800 3500);
FORCEPROP 2 LAST SEC 3
J 0
(4800 3500);
DISPLAY 0.680851 (4800 3500);
PAINT MONO (4800 3500);
DISPLAY INVISIBLE (4800 3500);
FORCEPROP 2 LAST CDS_LOCATION J6M1
J 0
(4800 3450);
DISPLAY 0.617021 (4800 3450);
PAINT AQUA (4800 3450);
DISPLAY INVISIBLE (4800 3450);
FORCEPROP 1 LAST PATH I44
J 0
(5250 3400);
PAINT GREEN (5250 3400);
DISPLAY INVISIBLE (5250 3400);
FORCEPROP 2 LAST ROOM DDR4_CH_D
J 0
(5250 2050);
PAINT ORANGE (5250 2050);
DISPLAY INVISIBLE (5250 2050);
FORCEADD GND..1
R 2
(4550 750);
FORCEPROP 3 LASTPIN (4550 800) SIG_NAME GND\g
J 0
(4560 810);
DISPLAY 0.659574 (4560 810);
PAINT MONO (4560 810);
DISPLAY INVISIBLE (4560 810);
FORCEPROP 1 LAST VOLTAGE 0
J 0
(4550 750);
PAINT SKYBLUE (4550 750);
DISPLAY INVISIBLE (4550 750);
FORCEPROP 2 LAST BOM_COST MEM
J 0
(4550 755);
PAINT ORANGE (4550 755);
DISPLAY INVISIBLE (4550 755);
FORCEPROP 2 LAST CDS_LIB mstr_symbols
J 0
(4550 750);
DISPLAY 0.787234 (4550 750);
PAINT MONO (4550 750);
DISPLAY INVISIBLE (4550 750);
FORCEPROP 1 LAST SIZE 1B
J 2
(4475 700);
DISPLAY 1.170213 (4475 700);
PAINT GREEN (4475 700);
DISPLAY INVISIBLE (4475 700);
FORCEPROP 1 LAST BODY_TYPE PLUMBING
J 2
(4595 707);
DISPLAY 0.340426 (4595 707);
PAINT GREEN (4595 707);
DISPLAY INVISIBLE (4595 707);
FORCEPROP 1 LAST PATH I45
J 2
(4475 750);
DISPLAY 0.872340 (4475 750);
PAINT AQUA (4475 750);
DISPLAY INVISIBLE (4475 750);
FORCEPROP 2 LAST ROOM DDR4_CH_B
J 0
(4550 755);
PAINT ORANGE (4550 755);
DISPLAY INVISIBLE (4550 755);
FORCEPROP 1 LAST HDL_POWER GND
J 2
(4550 900);
DISPLAY 0.553191 (4550 900);
PAINT GREEN (4550 900);
DISPLAY INVISIBLE (4550 900);
FORCEADD SCONN288_H44441003..2
(3400 3950);
FORCEPROP 1 LAST LOCATION J6M1
J 0
(3000 5050);
DISPLAY 0.617021 (3000 5050);
PAINT AQUA (3000 5050);
FORCEPROP 1 LAST MATERIAL SCONN
J 0
(3000 5000);
DISPLAY 0.617021 (3000 5000);
PAINT SKYBLUE (3000 5000);
FORCEPROP 2 LASTPIN (3850 4800) $PN 51
J 0
(3860 4810);
DISPLAY 0.617021 (3860 4810);
PAINT ORANGE (3860 4810);
FORCEPROP 2 LASTPIN (3850 4750) $PN 52
J 0
(3860 4760);
DISPLAY 0.617021 (3860 4760);
PAINT ORANGE (3860 4760);
FORCEPROP 2 LASTPIN (3850 4700) $PN 132
J 0
(3860 4710);
DISPLAY 0.617021 (3860 4710);
PAINT ORANGE (3860 4710);
FORCEPROP 2 LASTPIN (3850 4650) $PN 133
J 0
(3860 4660);
DISPLAY 0.617021 (3860 4660);
PAINT ORANGE (3860 4660);
FORCEPROP 2 LASTPIN (3850 4600) $PN 121
J 0
(3860 4610);
DISPLAY 0.617021 (3860 4610);
PAINT ORANGE (3860 4610);
FORCEPROP 2 LASTPIN (3850 4550) $PN 122
J 0
(3860 4560);
DISPLAY 0.617021 (3860 4560);
PAINT ORANGE (3860 4560);
FORCEPROP 2 LASTPIN (3850 4500) $PN 110
J 0
(3860 4510);
DISPLAY 0.617021 (3860 4510);
PAINT ORANGE (3860 4510);
FORCEPROP 2 LASTPIN (3850 4450) $PN 111
J 0
(3860 4460);
DISPLAY 0.617021 (3860 4460);
PAINT ORANGE (3860 4460);
FORCEPROP 2 LASTPIN (3850 4400) $PN 99
J 0
(3860 4410);
DISPLAY 0.617021 (3860 4410);
PAINT ORANGE (3860 4410);
FORCEPROP 2 LASTPIN (3850 4350) $PN 100
J 0
(3860 4360);
DISPLAY 0.617021 (3860 4360);
PAINT ORANGE (3860 4360);
FORCEPROP 2 LASTPIN (3850 4250) $PN 41
J 0
(3860 4260);
DISPLAY 0.617021 (3860 4260);
PAINT ORANGE (3860 4260);
FORCEPROP 2 LASTPIN (3850 4200) $PN 29
J 0
(3860 4210);
DISPLAY 0.617021 (3860 4210);
PAINT ORANGE (3860 4210);
FORCEPROP 2 LASTPIN (3850 4150) $PN 30
J 0
(3860 4160);
DISPLAY 0.617021 (3860 4160);
PAINT ORANGE (3860 4160);
FORCEPROP 2 LASTPIN (3850 4050) $PN 19
J 0
(3860 4060);
DISPLAY 0.617021 (3860 4060);
PAINT ORANGE (3860 4060);
FORCEPROP 2 LASTPIN (3850 4000) $PN 7
J 0
(3860 4010);
DISPLAY 0.617021 (3860 4010);
PAINT ORANGE (3860 4010);
FORCEPROP 2 LASTPIN (3850 3950) $PN 8
J 0
(3860 3960);
DISPLAY 0.617021 (3860 3960);
PAINT ORANGE (3860 3960);
FORCEPROP 2 LASTPIN (3850 3900) $PN 197
J 0
(3860 3910);
DISPLAY 0.617021 (3860 3910);
PAINT ORANGE (3860 3910);
FORCEPROP 2 LASTPIN (3850 3850) $PN 196
J 0
(3860 3860);
DISPLAY 0.617021 (3860 3860);
PAINT ORANGE (3860 3860);
FORCEPROP 2 LASTPIN (3850 3800) $PN 278
J 0
(3860 3810);
DISPLAY 0.617021 (3860 3810);
PAINT ORANGE (3860 3810);
FORCEPROP 2 LASTPIN (3850 3750) $PN 277
J 0
(3860 3760);
DISPLAY 0.617021 (3860 3760);
PAINT ORANGE (3860 3760);
FORCEPROP 2 LASTPIN (3850 3700) $PN 267
J 0
(3860 3710);
DISPLAY 0.617021 (3860 3710);
PAINT ORANGE (3860 3710);
FORCEPROP 2 LASTPIN (3850 3650) $PN 266
J 0
(3860 3660);
DISPLAY 0.617021 (3860 3660);
PAINT ORANGE (3860 3660);
FORCEPROP 2 LASTPIN (3850 3600) $PN 256
J 0
(3860 3610);
DISPLAY 0.617021 (3860 3610);
PAINT ORANGE (3860 3610);
FORCEPROP 2 LASTPIN (3850 3550) $PN 255
J 0
(3860 3560);
DISPLAY 0.617021 (3860 3560);
PAINT ORANGE (3860 3560);
FORCEPROP 2 LASTPIN (3850 3500) $PN 245
J 0
(3860 3510);
DISPLAY 0.617021 (3860 3510);
PAINT ORANGE (3860 3510);
FORCEPROP 2 LASTPIN (3850 3450) $PN 244
J 0
(3860 3460);
DISPLAY 0.617021 (3860 3460);
PAINT ORANGE (3860 3460);
FORCEPROP 2 LASTPIN (3850 3400) $PN 186
J 0
(3860 3410);
DISPLAY 0.617021 (3860 3410);
PAINT ORANGE (3860 3410);
FORCEPROP 2 LASTPIN (3850 3350) $PN 185
J 0
(3860 3360);
DISPLAY 0.617021 (3860 3360);
PAINT ORANGE (3860 3360);
FORCEPROP 2 LASTPIN (3850 3250) $PN 174
J 0
(3860 3260);
DISPLAY 0.617021 (3860 3260);
PAINT ORANGE (3860 3260);
FORCEPROP 2 LASTPIN (3850 3200) $PN 164
J 0
(3860 3210);
DISPLAY 0.617021 (3860 3210);
PAINT ORANGE (3860 3210);
FORCEPROP 2 LASTPIN (3850 3150) $PN 163
J 0
(3860 3160);
DISPLAY 0.617021 (3860 3160);
PAINT ORANGE (3860 3160);
FORCEPROP 2 LASTPIN (3850 3050) $PN 152
J 0
(3860 3060);
DISPLAY 0.617021 (3860 3060);
PAINT ORANGE (3860 3060);
FORCEPROP 2 LASTPIN (3850 4100) $PN 18
J 0
(3860 4110);
DISPLAY 0.617021 (3860 4110);
PAINT ORANGE (3860 4110);
FORCEPROP 2 LASTPIN (3850 3300) $PN 175
J 0
(3860 3310);
DISPLAY 0.617021 (3860 3310);
PAINT ORANGE (3860 3310);
FORCEPROP 2 LASTPIN (3850 4300) $PN 40
J 0
(3860 4310);
DISPLAY 0.617021 (3860 4310);
PAINT ORANGE (3860 4310);
FORCEPROP 2 LASTPIN (3850 3100) $PN 153
J 0
(3860 3110);
DISPLAY 0.617021 (3860 3110);
PAINT ORANGE (3860 3110);
FORCEPROP 0 LAST BOM_SS NOPOP
J 0
(3310 5042);
DISPLAY 1.021277 (3310 5042);
PAINT BROWN (3310 5042);
DISPLAY BOTH (3310 5042);
FORCEPROP 1 LAST PART_NUMBER H44441-003
J 0
(3000 2850);
DISPLAY 0.617021 (3000 2850);
PAINT BLUE (3000 2850);
FORCEPROP 1 LAST PACK_TYPE PIP
J 0
(3000 5100);
PAINT SKYBLUE (3000 5100);
DISPLAY INVISIBLE (3000 5100);
FORCEPROP 2 LAST BOM_COST MEM
J 0
(3400 3950);
PAINT ORANGE (3400 3950);
DISPLAY INVISIBLE (3400 3950);
FORCEPROP 2 LAST CDS_LIB mstr_sconn
J 0
(3400 3950);
PAINT ORANGE (3400 3950);
DISPLAY INVISIBLE (3400 3950);
FORCEPROP 2 LAST SEC_TYPE PIP
J 0
(3000 5100);
DISPLAY 1.021277 (3000 5100);
PAINT ORANGE (3000 5100);
DISPLAY INVISIBLE (3000 5100);
FORCEPROP 2 LAST SEC 2
J 0
(3000 5100);
DISPLAY 0.680851 (3000 5100);
PAINT MONO (3000 5100);
DISPLAY INVISIBLE (3000 5100);
FORCEPROP 2 LAST CDS_LOCATION J6M1
J 0
(3000 5050);
DISPLAY 0.617021 (3000 5050);
PAINT AQUA (3000 5050);
DISPLAY INVISIBLE (3000 5050);
FORCEPROP 1 LAST PATH I46
J 0
(3400 5000);
PAINT GREEN (3400 5000);
DISPLAY INVISIBLE (3400 5000);
FORCEPROP 2 LAST ROOM DDR4_CH_D
J 0
(3400 3950);
PAINT ORANGE (3400 3950);
DISPLAY INVISIBLE (3400 3950);
FORCEADD PVPP_DEF..1
(2700 2550);
FORCEPROP 3 LASTPIN (2700 2500) SIG_NAME PVPP_DEF\g
J 0
(2710 2510);
DISPLAY 0.659574 (2710 2510);
PAINT MONO (2710 2510);
DISPLAY INVISIBLE (2710 2510);
FORCEPROP 1 LAST VOLTAGE 2.5V
J 0
(2655 2507);
DISPLAY 0.340426 (2655 2507);
PAINT SKYBLUE (2655 2507);
DISPLAY INVISIBLE (2655 2507);
FORCEPROP 0 LAST BOM_COST MEM
J 0
(2700 2650);
PAINT ORANGE (2700 2650);
DISPLAY INVISIBLE (2700 2650);
FORCEPROP 2 LAST CDS_LIB mstr_symbols
J 0
(2700 2550);
PAINT ORANGE (2700 2550);
DISPLAY INVISIBLE (2700 2550);
FORCEPROP 1 LAST BODY_TYPE PLUMBING
J 0
(2655 2507);
DISPLAY 0.340426 (2655 2507);
PAINT GREEN (2655 2507);
DISPLAY INVISIBLE (2655 2507);
FORCEPROP 1 LAST PATH I47
J 0
(2750 2575);
DISPLAY 0.872340 (2750 2575);
PAINT AQUA (2750 2575);
DISPLAY INVISIBLE (2750 2575);
FORCEPROP 2 LAST ROOM DDR4_CH_B
J 0
(2700 2650);
PAINT ORANGE (2700 2650);
DISPLAY INVISIBLE (2700 2650);
FORCEPROP 1 LAST HDL_POWER PVPP_DEF
J 1
(2700 2600);
DISPLAY 0.872340 (2700 2600);
PAINT GREEN (2700 2600);
DISPLAY INVISIBLE (2700 2600);
FORCEADD PVTT_DEF..1
(2550 2250);
FORCEPROP 3 LASTPIN (2550 2200) SIG_NAME PVTT_DEF\g
J 0
(2560 2210);
DISPLAY 0.659574 (2560 2210);
PAINT MONO (2560 2210);
DISPLAY INVISIBLE (2560 2210);
FORCEPROP 1 LAST VOLTAGE 0.6V
J 0
(2505 2207);
DISPLAY 0.340426 (2505 2207);
PAINT SKYBLUE (2505 2207);
DISPLAY INVISIBLE (2505 2207);
FORCEPROP 2 LAST BOM_COST MEM
J 0
(2550 2255);
PAINT ORANGE (2550 2255);
DISPLAY INVISIBLE (2550 2255);
FORCEPROP 2 LAST CDS_LIB mstr_symbols
J 0
(2550 2250);
PAINT ORANGE (2550 2250);
DISPLAY INVISIBLE (2550 2250);
FORCEPROP 1 LAST BODY_TYPE PLUMBING
J 0
(2505 2207);
DISPLAY 0.340426 (2505 2207);
PAINT GREEN (2505 2207);
DISPLAY INVISIBLE (2505 2207);
FORCEPROP 1 LAST PATH I48
J 0
(2600 2275);
DISPLAY 0.872340 (2600 2275);
PAINT AQUA (2600 2275);
DISPLAY INVISIBLE (2600 2275);
FORCEPROP 2 LAST ROOM DDR4_CH_B
J 0
(2550 2350);
DISPLAY 0.787234 (2550 2350);
PAINT ORANGE (2550 2350);
DISPLAY INVISIBLE (2550 2350);
FORCEPROP 1 LAST HDL_POWER PVTT_DEF
J 1
(2550 2300);
DISPLAY 0.872340 (2550 2300);
PAINT GREEN (2550 2300);
DISPLAY INVISIBLE (2550 2300);
FORCEADD PVDDQ_DEF..1
(2300 2100);
FORCEPROP 3 LASTPIN (2300 2050) SIG_NAME PVDDQ_DEF\g
J 0
(2310 2060);
DISPLAY 0.659574 (2310 2060);
PAINT MONO (2310 2060);
DISPLAY INVISIBLE (2310 2060);
FORCEPROP 1 LAST VOLTAGE 1.2V
J 0
(2255 2057);
DISPLAY 0.340426 (2255 2057);
PAINT SKYBLUE (2255 2057);
DISPLAY INVISIBLE (2255 2057);
FORCEPROP 2 LAST BOM_COST MEM
J 0
(2300 2105);
PAINT ORANGE (2300 2105);
DISPLAY INVISIBLE (2300 2105);
FORCEPROP 2 LAST CDS_LIB mstr_symbols
J 0
(2300 2100);
PAINT ORANGE (2300 2100);
DISPLAY INVISIBLE (2300 2100);
FORCEPROP 1 LAST BODY_TYPE PLUMBING
J 0
(2255 2057);
DISPLAY 0.340426 (2255 2057);
PAINT GREEN (2255 2057);
DISPLAY INVISIBLE (2255 2057);
FORCEPROP 1 LAST PATH I49
J 0
(2350 2125);
DISPLAY 0.872340 (2350 2125);
PAINT AQUA (2350 2125);
DISPLAY INVISIBLE (2350 2125);
FORCEPROP 2 LAST ROOM DDR4_CH_B
J 0
(2300 2200);
DISPLAY 0.787234 (2300 2200);
PAINT ORANGE (2300 2200);
DISPLAY INVISIBLE (2300 2200);
FORCEPROP 1 LAST HDL_POWER PVDDQ_DEF
J 1
(2300 2150);
DISPLAY 0.872340 (2300 2150);
PAINT GREEN (2300 2150);
DISPLAY INVISIBLE (2300 2150);
FORCEADD TAP..6
R 2
(4350 4650);
FORCEPROP 3 LASTPIN (4300 4650) SIG_NAME M_D_DQS_DN<16>
J 0
(4310 4660);
DISPLAY 0.659574 (4310 4660);
PAINT MONO (4310 4660);
DISPLAY INVISIBLE (4310 4660);
FORCEPROP 1 LASTPIN (4300 4650) BN 16
J 2
(4350 4660);
DISPLAY 0.617021 (4350 4660);
PAINT PINK (4350 4660);
FORCEPROP 2 LAST CDS_LIB mstr_standard
J 0
(4350 4650);
DISPLAY 0.787234 (4350 4650);
PAINT MONO (4350 4650);
DISPLAY INVISIBLE (4350 4650);
FORCEPROP 1 LAST BODY_TYPE PLUMBING
J 2
(4350 4600);
DISPLAY 1.234043 (4350 4600);
PAINT GREEN (4350 4600);
DISPLAY INVISIBLE (4350 4600);
FORCEPROP 1 LAST HDL_TAP TRUE
J 2
(4025 4525);
DISPLAY 1.234043 (4025 4525);
PAINT GREEN (4025 4525);
DISPLAY INVISIBLE (4025 4525);
FORCEPROP 1 LAST PATH I5
J 2
(4352 4650);
DISPLAY 0.872340 (4352 4650);
PAINT GREEN (4352 4650);
DISPLAY INVISIBLE (4352 4650);
FORCEADD SCONN288_H44441003..4
(3400 1550);
FORCEPROP 1 LAST LOCATION J6M1
J 0
(2950 2650);
DISPLAY 0.617021 (2950 2650);
PAINT AQUA (2950 2650);
FORCEPROP 1 LAST PART_NUMBER H44441-003
J 0
(2950 500);
DISPLAY 0.617021 (2950 500);
PAINT BLUE (2950 500);
FORCEPROP 1 LAST MATERIAL SCONN
J 0
(2950 2600);
DISPLAY 0.617021 (2950 2600);
PAINT SKYBLUE (2950 2600);
FORCEPROP 2 LASTPIN (2900 2100) $PN 77
J 2
(2890 2110);
DISPLAY 0.617021 (2890 2110);
PAINT ORANGE (2890 2110);
FORCEPROP 2 LASTPIN (2900 2050) $PN 221
J 2
(2890 2060);
DISPLAY 0.617021 (2890 2060);
PAINT ORANGE (2890 2060);
FORCEPROP 2 LASTPIN (2900 2400) $PN 142
J 2
(2890 2410);
DISPLAY 0.617021 (2890 2410);
PAINT ORANGE (2890 2410);
FORCEPROP 2 LASTPIN (2900 2350) $PN 143
J 2
(2890 2360);
DISPLAY 0.617021 (2890 2360);
PAINT ORANGE (2890 2360);
FORCEPROP 2 LASTPIN (2900 2300) $PN 288
J 2
(2890 2310);
DISPLAY 0.617021 (2890 2310);
PAINT ORANGE (2890 2310);
FORCEPROP 2 LASTPIN (2900 2250) $PN 286
J 2
(2890 2260);
DISPLAY 0.617021 (2890 2260);
PAINT ORANGE (2890 2260);
FORCEPROP 2 LASTPIN (2900 2200) $PN 287
J 2
(2890 2210);
DISPLAY 0.617021 (2890 2210);
PAINT ORANGE (2890 2210);
FORCEPROP 2 LASTPIN (2900 1950) $PN 59
J 2
(2890 1960);
DISPLAY 0.617021 (2890 1960);
PAINT ORANGE (2890 1960);
FORCEPROP 2 LASTPIN (2900 1900) $PN 61
J 2
(2890 1910);
DISPLAY 0.617021 (2890 1910);
PAINT ORANGE (2890 1910);
FORCEPROP 2 LASTPIN (2900 1850) $PN 64
J 2
(2890 1860);
DISPLAY 0.617021 (2890 1860);
PAINT ORANGE (2890 1860);
FORCEPROP 2 LASTPIN (2900 1800) $PN 67
J 2
(2890 1810);
DISPLAY 0.617021 (2890 1810);
PAINT ORANGE (2890 1810);
FORCEPROP 2 LASTPIN (2900 1750) $PN 70
J 2
(2890 1760);
DISPLAY 0.617021 (2890 1760);
PAINT ORANGE (2890 1760);
FORCEPROP 2 LASTPIN (2900 1700) $PN 73
J 2
(2890 1710);
DISPLAY 0.617021 (2890 1710);
PAINT ORANGE (2890 1710);
FORCEPROP 2 LASTPIN (2900 1650) $PN 76
J 2
(2890 1660);
DISPLAY 0.617021 (2890 1660);
PAINT ORANGE (2890 1660);
FORCEPROP 2 LASTPIN (2900 1600) $PN 80
J 2
(2890 1610);
DISPLAY 0.617021 (2890 1610);
PAINT ORANGE (2890 1610);
FORCEPROP 2 LASTPIN (2900 1550) $PN 83
J 2
(2890 1560);
DISPLAY 0.617021 (2890 1560);
PAINT ORANGE (2890 1560);
FORCEPROP 2 LASTPIN (2900 1500) $PN 85
J 2
(2890 1510);
DISPLAY 0.617021 (2890 1510);
PAINT ORANGE (2890 1510);
FORCEPROP 2 LASTPIN (2900 1450) $PN 88
J 2
(2890 1460);
DISPLAY 0.617021 (2890 1460);
PAINT ORANGE (2890 1460);
FORCEPROP 2 LASTPIN (2900 1400) $PN 90
J 2
(2890 1410);
DISPLAY 0.617021 (2890 1410);
PAINT ORANGE (2890 1410);
FORCEPROP 2 LASTPIN (2900 1350) $PN 92
J 2
(2890 1360);
DISPLAY 0.617021 (2890 1360);
PAINT ORANGE (2890 1360);
FORCEPROP 2 LASTPIN (2900 1300) $PN 204
J 2
(2890 1310);
DISPLAY 0.617021 (2890 1310);
PAINT ORANGE (2890 1310);
FORCEPROP 2 LASTPIN (2900 1200) $PN 209
J 2
(2890 1210);
DISPLAY 0.617021 (2890 1210);
PAINT ORANGE (2890 1210);
FORCEPROP 2 LASTPIN (2900 1150) $PN 212
J 2
(2890 1160);
DISPLAY 0.617021 (2890 1160);
PAINT ORANGE (2890 1160);
FORCEPROP 2 LASTPIN (2900 1050) $PN 217
J 2
(2890 1060);
DISPLAY 0.617021 (2890 1060);
PAINT ORANGE (2890 1060);
FORCEPROP 2 LASTPIN (2900 1000) $PN 220
J 2
(2890 1010);
DISPLAY 0.617021 (2890 1010);
PAINT ORANGE (2890 1010);
FORCEPROP 2 LASTPIN (2900 950) $PN 223
J 2
(2890 960);
DISPLAY 0.617021 (2890 960);
PAINT ORANGE (2890 960);
FORCEPROP 2 LASTPIN (2900 850) $PN 229
J 2
(2890 860);
DISPLAY 0.617021 (2890 860);
PAINT ORANGE (2890 860);
FORCEPROP 2 LASTPIN (2900 800) $PN 231
J 2
(2890 810);
DISPLAY 0.617021 (2890 810);
PAINT ORANGE (2890 810);
FORCEPROP 2 LASTPIN (2900 750) $PN 233
J 2
(2890 760);
DISPLAY 0.617021 (2890 760);
PAINT ORANGE (2890 760);
FORCEPROP 2 LASTPIN (2900 700) $PN 236
J 2
(2890 710);
DISPLAY 0.617021 (2890 710);
PAINT ORANGE (2890 710);
FORCEPROP 2 LASTPIN (3900 2400) $PN 1
J 0
(3910 2410);
DISPLAY 0.617021 (3910 2410);
PAINT ORANGE (3910 2410);
FORCEPROP 2 LASTPIN (3900 2350) $PN 145
J 0
(3910 2360);
DISPLAY 0.617021 (3910 2360);
PAINT ORANGE (3910 2360);
FORCEPROP 2 LASTPIN (2900 900) $PN 226
J 2
(2890 910);
DISPLAY 0.617021 (2890 910);
PAINT ORANGE (2890 910);
FORCEPROP 2 LASTPIN (2900 1250) $PN 206
J 2
(2890 1260);
DISPLAY 0.617021 (2890 1260);
PAINT ORANGE (2890 1260);
FORCEPROP 2 LASTPIN (2900 1100) $PN 215
J 2
(2890 1110);
DISPLAY 0.617021 (2890 1110);
PAINT ORANGE (2890 1110);
FORCEPROP 0 LAST BOM_SS NOPOP
J 0
(3160 2642);
DISPLAY 1.021277 (3160 2642);
PAINT BROWN (3160 2642);
DISPLAY BOTH (3160 2642);
FORCEPROP 1 LAST PACK_TYPE PIP
J 0
(2950 2700);
PAINT SKYBLUE (2950 2700);
DISPLAY INVISIBLE (2950 2700);
FORCEPROP 2 LAST BOM_COST MEM
J 0
(3400 1550);
PAINT ORANGE (3400 1550);
DISPLAY INVISIBLE (3400 1550);
FORCEPROP 2 LAST CDS_LIB mstr_sconn
J 0
(3400 1550);
PAINT ORANGE (3400 1550);
DISPLAY INVISIBLE (3400 1550);
FORCEPROP 2 LAST SEC_TYPE PIP
J 0
(2950 2700);
DISPLAY 1.021277 (2950 2700);
PAINT ORANGE (2950 2700);
DISPLAY INVISIBLE (2950 2700);
FORCEPROP 2 LAST SEC 4
J 0
(2950 2700);
DISPLAY 0.680851 (2950 2700);
PAINT MONO (2950 2700);
DISPLAY INVISIBLE (2950 2700);
FORCEPROP 2 LAST CDS_LOCATION J6M1
J 0
(2950 2650);
DISPLAY 0.617021 (2950 2650);
PAINT AQUA (2950 2650);
DISPLAY INVISIBLE (2950 2650);
FORCEPROP 1 LAST PATH I50
J 0
(3400 2600);
PAINT GREEN (3400 2600);
DISPLAY INVISIBLE (3400 2600);
FORCEPROP 2 LAST ROOM DDR4_CH_D
J 0
(3400 1550);
PAINT ORANGE (3400 1550);
DISPLAY INVISIBLE (3400 1550);
FORCEADD TAP..6
R 2
(1700 4700);
FORCEPROP 3 LASTPIN (1650 4700) SIG_NAME M_D_DQ<62>
J 0
(1660 4710);
DISPLAY 0.659574 (1660 4710);
PAINT MONO (1660 4710);
DISPLAY INVISIBLE (1660 4710);
FORCEPROP 1 LASTPIN (1650 4700) BN 62
J 2
(1700 4710);
DISPLAY 0.617021 (1700 4710);
PAINT PINK (1700 4710);
FORCEPROP 2 LAST CDS_LIB mstr_standard
J 2
(1700 4700);
DISPLAY 0.787234 (1700 4700);
PAINT MONO (1700 4700);
DISPLAY INVISIBLE (1700 4700);
FORCEPROP 1 LAST BODY_TYPE PLUMBING
J 2
(1700 4650);
DISPLAY 1.234043 (1700 4650);
PAINT GREEN (1700 4650);
DISPLAY INVISIBLE (1700 4650);
FORCEPROP 1 LAST HDL_TAP TRUE
J 2
(1375 4575);
DISPLAY 1.234043 (1375 4575);
PAINT GREEN (1375 4575);
DISPLAY INVISIBLE (1375 4575);
FORCEPROP 1 LAST PATH I51
J 2
(1702 4700);
DISPLAY 0.872340 (1702 4700);
PAINT GREEN (1702 4700);
DISPLAY INVISIBLE (1702 4700);
FORCEADD TAP..6
R 2
(1700 4600);
FORCEPROP 3 LASTPIN (1650 4600) SIG_NAME M_D_DQ<60>
J 0
(1660 4610);
DISPLAY 0.659574 (1660 4610);
PAINT MONO (1660 4610);
DISPLAY INVISIBLE (1660 4610);
FORCEPROP 1 LASTPIN (1650 4600) BN 60
J 2
(1700 4610);
DISPLAY 0.617021 (1700 4610);
PAINT PINK (1700 4610);
FORCEPROP 2 LAST CDS_LIB mstr_standard
J 2
(1700 4600);
DISPLAY 0.787234 (1700 4600);
PAINT MONO (1700 4600);
DISPLAY INVISIBLE (1700 4600);
FORCEPROP 1 LAST BODY_TYPE PLUMBING
J 2
(1700 4550);
DISPLAY 1.234043 (1700 4550);
PAINT GREEN (1700 4550);
DISPLAY INVISIBLE (1700 4550);
FORCEPROP 1 LAST HDL_TAP TRUE
J 2
(1375 4475);
DISPLAY 1.234043 (1375 4475);
PAINT GREEN (1375 4475);
DISPLAY INVISIBLE (1375 4475);
FORCEPROP 1 LAST PATH I52
J 2
(1702 4600);
DISPLAY 0.872340 (1702 4600);
PAINT GREEN (1702 4600);
DISPLAY INVISIBLE (1702 4600);
FORCEADD TAP..6
R 2
(1700 4650);
FORCEPROP 3 LASTPIN (1650 4650) SIG_NAME M_D_DQ<61>
J 0
(1660 4660);
DISPLAY 0.659574 (1660 4660);
PAINT MONO (1660 4660);
DISPLAY INVISIBLE (1660 4660);
FORCEPROP 1 LASTPIN (1650 4650) BN 61
J 2
(1700 4660);
DISPLAY 0.617021 (1700 4660);
PAINT PINK (1700 4660);
FORCEPROP 2 LAST CDS_LIB mstr_standard
J 2
(1700 4650);
DISPLAY 0.787234 (1700 4650);
PAINT MONO (1700 4650);
DISPLAY INVISIBLE (1700 4650);
FORCEPROP 1 LAST BODY_TYPE PLUMBING
J 2
(1700 4600);
DISPLAY 1.234043 (1700 4600);
PAINT GREEN (1700 4600);
DISPLAY INVISIBLE (1700 4600);
FORCEPROP 1 LAST HDL_TAP TRUE
J 2
(1375 4525);
DISPLAY 1.234043 (1375 4525);
PAINT GREEN (1375 4525);
DISPLAY INVISIBLE (1375 4525);
FORCEPROP 1 LAST PATH I53
J 2
(1702 4650);
DISPLAY 0.872340 (1702 4650);
PAINT GREEN (1702 4650);
DISPLAY INVISIBLE (1702 4650);
FORCEADD TAP..6
R 2
(1700 4750);
FORCEPROP 3 LASTPIN (1650 4750) SIG_NAME M_D_DQ<63>
J 0
(1660 4760);
DISPLAY 0.659574 (1660 4760);
PAINT MONO (1660 4760);
DISPLAY INVISIBLE (1660 4760);
FORCEPROP 1 LASTPIN (1650 4750) BN 63
J 2
(1700 4760);
DISPLAY 0.617021 (1700 4760);
PAINT PINK (1700 4760);
FORCEPROP 2 LAST CDS_LIB mstr_standard
J 2
(1700 4750);
DISPLAY 0.787234 (1700 4750);
PAINT MONO (1700 4750);
DISPLAY INVISIBLE (1700 4750);
FORCEPROP 1 LAST BODY_TYPE PLUMBING
J 2
(1700 4700);
DISPLAY 1.234043 (1700 4700);
PAINT GREEN (1700 4700);
DISPLAY INVISIBLE (1700 4700);
FORCEPROP 1 LAST HDL_TAP TRUE
J 2
(1375 4625);
DISPLAY 1.234043 (1375 4625);
PAINT GREEN (1375 4625);
DISPLAY INVISIBLE (1375 4625);
FORCEPROP 1 LAST PATH I54
J 2
(1702 4750);
DISPLAY 0.872340 (1702 4750);
PAINT GREEN (1702 4750);
DISPLAY INVISIBLE (1702 4750);
FORCEADD TAP..6
R 2
(1700 4350);
FORCEPROP 3 LASTPIN (1650 4350) SIG_NAME M_D_DQ<55>
J 0
(1660 4360);
DISPLAY 0.659574 (1660 4360);
PAINT MONO (1660 4360);
DISPLAY INVISIBLE (1660 4360);
FORCEPROP 1 LASTPIN (1650 4350) BN 55
J 2
(1700 4360);
DISPLAY 0.617021 (1700 4360);
PAINT PINK (1700 4360);
FORCEPROP 2 LAST CDS_LIB mstr_standard
J 2
(1700 4350);
DISPLAY 0.787234 (1700 4350);
PAINT MONO (1700 4350);
DISPLAY INVISIBLE (1700 4350);
FORCEPROP 1 LAST BODY_TYPE PLUMBING
J 2
(1700 4300);
DISPLAY 1.234043 (1700 4300);
PAINT GREEN (1700 4300);
DISPLAY INVISIBLE (1700 4300);
FORCEPROP 1 LAST HDL_TAP TRUE
J 2
(1375 4225);
DISPLAY 1.234043 (1375 4225);
PAINT GREEN (1375 4225);
DISPLAY INVISIBLE (1375 4225);
FORCEPROP 1 LAST PATH I55
J 2
(1702 4350);
DISPLAY 0.872340 (1702 4350);
PAINT GREEN (1702 4350);
DISPLAY INVISIBLE (1702 4350);
FORCEADD TAP..6
R 2
(1700 4400);
FORCEPROP 3 LASTPIN (1650 4400) SIG_NAME M_D_DQ<56>
J 0
(1660 4410);
DISPLAY 0.659574 (1660 4410);
PAINT MONO (1660 4410);
DISPLAY INVISIBLE (1660 4410);
FORCEPROP 1 LASTPIN (1650 4400) BN 56
J 2
(1700 4410);
DISPLAY 0.617021 (1700 4410);
PAINT PINK (1700 4410);
FORCEPROP 2 LAST CDS_LIB mstr_standard
J 2
(1700 4400);
DISPLAY 0.787234 (1700 4400);
PAINT MONO (1700 4400);
DISPLAY INVISIBLE (1700 4400);
FORCEPROP 1 LAST BODY_TYPE PLUMBING
J 2
(1700 4350);
DISPLAY 1.234043 (1700 4350);
PAINT GREEN (1700 4350);
DISPLAY INVISIBLE (1700 4350);
FORCEPROP 1 LAST HDL_TAP TRUE
J 2
(1375 4275);
DISPLAY 1.234043 (1375 4275);
PAINT GREEN (1375 4275);
DISPLAY INVISIBLE (1375 4275);
FORCEPROP 1 LAST PATH I56
J 2
(1702 4400);
DISPLAY 0.872340 (1702 4400);
PAINT GREEN (1702 4400);
DISPLAY INVISIBLE (1702 4400);
FORCEADD TAP..6
R 2
(1700 4450);
FORCEPROP 3 LASTPIN (1650 4450) SIG_NAME M_D_DQ<57>
J 0
(1660 4460);
DISPLAY 0.659574 (1660 4460);
PAINT MONO (1660 4460);
DISPLAY INVISIBLE (1660 4460);
FORCEPROP 1 LASTPIN (1650 4450) BN 57
J 2
(1700 4460);
DISPLAY 0.617021 (1700 4460);
PAINT PINK (1700 4460);
FORCEPROP 2 LAST CDS_LIB mstr_standard
J 2
(1700 4450);
DISPLAY 0.787234 (1700 4450);
PAINT MONO (1700 4450);
DISPLAY INVISIBLE (1700 4450);
FORCEPROP 1 LAST BODY_TYPE PLUMBING
J 2
(1700 4400);
DISPLAY 1.234043 (1700 4400);
PAINT GREEN (1700 4400);
DISPLAY INVISIBLE (1700 4400);
FORCEPROP 1 LAST HDL_TAP TRUE
J 2
(1375 4325);
DISPLAY 1.234043 (1375 4325);
PAINT GREEN (1375 4325);
DISPLAY INVISIBLE (1375 4325);
FORCEPROP 1 LAST PATH I57
J 2
(1702 4450);
DISPLAY 0.872340 (1702 4450);
PAINT GREEN (1702 4450);
DISPLAY INVISIBLE (1702 4450);
FORCEADD TAP..6
R 2
(1700 4550);
FORCEPROP 3 LASTPIN (1650 4550) SIG_NAME M_D_DQ<59>
J 0
(1660 4560);
DISPLAY 0.659574 (1660 4560);
PAINT MONO (1660 4560);
DISPLAY INVISIBLE (1660 4560);
FORCEPROP 1 LASTPIN (1650 4550) BN 59
J 2
(1700 4560);
DISPLAY 0.617021 (1700 4560);
PAINT PINK (1700 4560);
FORCEPROP 2 LAST CDS_LIB mstr_standard
J 2
(1700 4550);
DISPLAY 0.787234 (1700 4550);
PAINT MONO (1700 4550);
DISPLAY INVISIBLE (1700 4550);
FORCEPROP 1 LAST BODY_TYPE PLUMBING
J 2
(1700 4500);
DISPLAY 1.234043 (1700 4500);
PAINT GREEN (1700 4500);
DISPLAY INVISIBLE (1700 4500);
FORCEPROP 1 LAST HDL_TAP TRUE
J 2
(1375 4425);
DISPLAY 1.234043 (1375 4425);
PAINT GREEN (1375 4425);
DISPLAY INVISIBLE (1375 4425);
FORCEPROP 1 LAST PATH I58
J 2
(1702 4550);
DISPLAY 0.872340 (1702 4550);
PAINT GREEN (1702 4550);
DISPLAY INVISIBLE (1702 4550);
FORCEADD TAP..6
R 2
(1700 4500);
FORCEPROP 3 LASTPIN (1650 4500) SIG_NAME M_D_DQ<58>
J 0
(1660 4510);
DISPLAY 0.659574 (1660 4510);
PAINT MONO (1660 4510);
DISPLAY INVISIBLE (1660 4510);
FORCEPROP 1 LASTPIN (1650 4500) BN 58
J 2
(1700 4510);
DISPLAY 0.617021 (1700 4510);
PAINT PINK (1700 4510);
FORCEPROP 2 LAST CDS_LIB mstr_standard
J 2
(1700 4500);
DISPLAY 0.787234 (1700 4500);
PAINT MONO (1700 4500);
DISPLAY INVISIBLE (1700 4500);
FORCEPROP 1 LAST BODY_TYPE PLUMBING
J 2
(1700 4450);
DISPLAY 1.234043 (1700 4450);
PAINT GREEN (1700 4450);
DISPLAY INVISIBLE (1700 4450);
FORCEPROP 1 LAST HDL_TAP TRUE
J 2
(1375 4375);
DISPLAY 1.234043 (1375 4375);
PAINT GREEN (1375 4375);
DISPLAY INVISIBLE (1375 4375);
FORCEPROP 1 LAST PATH I59
J 2
(1702 4500);
DISPLAY 0.872340 (1702 4500);
PAINT GREEN (1702 4500);
DISPLAY INVISIBLE (1702 4500);
FORCEADD TAP..6
R 2
(4100 4800);
FORCEPROP 3 LASTPIN (4050 4800) SIG_NAME M_D_DQS_DP<17>
J 0
(4060 4810);
DISPLAY 0.659574 (4060 4810);
PAINT MONO (4060 4810);
DISPLAY INVISIBLE (4060 4810);
FORCEPROP 1 LASTPIN (4050 4800) BN 17
J 2
(4100 4810);
DISPLAY 0.617021 (4100 4810);
PAINT PINK (4100 4810);
FORCEPROP 2 LAST CDS_LIB mstr_standard
J 2
(4100 4800);
DISPLAY 0.787234 (4100 4800);
PAINT MONO (4100 4800);
DISPLAY INVISIBLE (4100 4800);
FORCEPROP 1 LAST BODY_TYPE PLUMBING
J 2
(4100 4750);
DISPLAY 1.234043 (4100 4750);
PAINT GREEN (4100 4750);
DISPLAY INVISIBLE (4100 4750);
FORCEPROP 1 LAST HDL_TAP TRUE
J 2
(3775 4675);
DISPLAY 1.234043 (3775 4675);
PAINT GREEN (3775 4675);
DISPLAY INVISIBLE (3775 4675);
FORCEPROP 1 LAST PATH I6
J 2
(4102 4800);
DISPLAY 0.872340 (4102 4800);
PAINT GREEN (4102 4800);
DISPLAY INVISIBLE (4102 4800);
FORCEADD TAP..6
R 2
(1700 4200);
FORCEPROP 3 LASTPIN (1650 4200) SIG_NAME M_D_DQ<52>
J 0
(1660 4210);
DISPLAY 0.659574 (1660 4210);
PAINT MONO (1660 4210);
DISPLAY INVISIBLE (1660 4210);
FORCEPROP 1 LASTPIN (1650 4200) BN 52
J 2
(1700 4210);
DISPLAY 0.617021 (1700 4210);
PAINT PINK (1700 4210);
FORCEPROP 2 LAST CDS_LIB mstr_standard
J 2
(1700 4200);
DISPLAY 0.787234 (1700 4200);
PAINT MONO (1700 4200);
DISPLAY INVISIBLE (1700 4200);
FORCEPROP 1 LAST BODY_TYPE PLUMBING
J 2
(1700 4150);
DISPLAY 1.234043 (1700 4150);
PAINT GREEN (1700 4150);
DISPLAY INVISIBLE (1700 4150);
FORCEPROP 1 LAST HDL_TAP TRUE
J 2
(1375 4075);
DISPLAY 1.234043 (1375 4075);
PAINT GREEN (1375 4075);
DISPLAY INVISIBLE (1375 4075);
FORCEPROP 1 LAST PATH I60
J 2
(1702 4200);
DISPLAY 0.872340 (1702 4200);
PAINT GREEN (1702 4200);
DISPLAY INVISIBLE (1702 4200);
FORCEADD TAP..6
R 2
(1700 4150);
FORCEPROP 3 LASTPIN (1650 4150) SIG_NAME M_D_DQ<51>
J 0
(1660 4160);
DISPLAY 0.659574 (1660 4160);
PAINT MONO (1660 4160);
DISPLAY INVISIBLE (1660 4160);
FORCEPROP 1 LASTPIN (1650 4150) BN 51
J 2
(1700 4160);
DISPLAY 0.617021 (1700 4160);
PAINT PINK (1700 4160);
FORCEPROP 2 LAST CDS_LIB mstr_standard
J 2
(1700 4150);
DISPLAY 0.787234 (1700 4150);
PAINT MONO (1700 4150);
DISPLAY INVISIBLE (1700 4150);
FORCEPROP 1 LAST BODY_TYPE PLUMBING
J 2
(1700 4100);
DISPLAY 1.234043 (1700 4100);
PAINT GREEN (1700 4100);
DISPLAY INVISIBLE (1700 4100);
FORCEPROP 1 LAST HDL_TAP TRUE
J 2
(1375 4025);
DISPLAY 1.234043 (1375 4025);
PAINT GREEN (1375 4025);
DISPLAY INVISIBLE (1375 4025);
FORCEPROP 1 LAST PATH I61
J 2
(1702 4150);
DISPLAY 0.872340 (1702 4150);
PAINT GREEN (1702 4150);
DISPLAY INVISIBLE (1702 4150);
FORCEADD TAP..6
R 2
(1700 4100);
FORCEPROP 3 LASTPIN (1650 4100) SIG_NAME M_D_DQ<50>
J 0
(1660 4110);
DISPLAY 0.659574 (1660 4110);
PAINT MONO (1660 4110);
DISPLAY INVISIBLE (1660 4110);
FORCEPROP 1 LASTPIN (1650 4100) BN 50
J 2
(1700 4110);
DISPLAY 0.617021 (1700 4110);
PAINT PINK (1700 4110);
FORCEPROP 2 LAST CDS_LIB mstr_standard
J 2
(1700 4100);
DISPLAY 0.787234 (1700 4100);
PAINT MONO (1700 4100);
DISPLAY INVISIBLE (1700 4100);
FORCEPROP 1 LAST BODY_TYPE PLUMBING
J 2
(1700 4050);
DISPLAY 1.234043 (1700 4050);
PAINT GREEN (1700 4050);
DISPLAY INVISIBLE (1700 4050);
FORCEPROP 1 LAST HDL_TAP TRUE
J 2
(1375 3975);
DISPLAY 1.234043 (1375 3975);
PAINT GREEN (1375 3975);
DISPLAY INVISIBLE (1375 3975);
FORCEPROP 1 LAST PATH I62
J 2
(1702 4100);
DISPLAY 0.872340 (1702 4100);
PAINT GREEN (1702 4100);
DISPLAY INVISIBLE (1702 4100);
FORCEADD TAP..6
R 2
(1700 4250);
FORCEPROP 3 LASTPIN (1650 4250) SIG_NAME M_D_DQ<53>
J 0
(1660 4260);
DISPLAY 0.659574 (1660 4260);
PAINT MONO (1660 4260);
DISPLAY INVISIBLE (1660 4260);
FORCEPROP 1 LASTPIN (1650 4250) BN 53
J 2
(1700 4260);
DISPLAY 0.617021 (1700 4260);
PAINT PINK (1700 4260);
FORCEPROP 2 LAST CDS_LIB mstr_standard
J 2
(1700 4250);
DISPLAY 0.787234 (1700 4250);
PAINT MONO (1700 4250);
DISPLAY INVISIBLE (1700 4250);
FORCEPROP 1 LAST BODY_TYPE PLUMBING
J 2
(1700 4200);
DISPLAY 1.234043 (1700 4200);
PAINT GREEN (1700 4200);
DISPLAY INVISIBLE (1700 4200);
FORCEPROP 1 LAST HDL_TAP TRUE
J 2
(1375 4125);
DISPLAY 1.234043 (1375 4125);
PAINT GREEN (1375 4125);
DISPLAY INVISIBLE (1375 4125);
FORCEPROP 1 LAST PATH I63
J 2
(1702 4250);
DISPLAY 0.872340 (1702 4250);
PAINT GREEN (1702 4250);
DISPLAY INVISIBLE (1702 4250);
FORCEADD TAP..6
R 2
(1700 4300);
FORCEPROP 3 LASTPIN (1650 4300) SIG_NAME M_D_DQ<54>
J 0
(1660 4310);
DISPLAY 0.659574 (1660 4310);
PAINT MONO (1660 4310);
DISPLAY INVISIBLE (1660 4310);
FORCEPROP 1 LASTPIN (1650 4300) BN 54
J 2
(1700 4310);
DISPLAY 0.617021 (1700 4310);
PAINT PINK (1700 4310);
FORCEPROP 2 LAST CDS_LIB mstr_standard
J 2
(1700 4300);
DISPLAY 0.787234 (1700 4300);
PAINT MONO (1700 4300);
DISPLAY INVISIBLE (1700 4300);
FORCEPROP 1 LAST BODY_TYPE PLUMBING
J 2
(1700 4250);
DISPLAY 1.234043 (1700 4250);
PAINT GREEN (1700 4250);
DISPLAY INVISIBLE (1700 4250);
FORCEPROP 1 LAST HDL_TAP TRUE
J 2
(1375 4175);
DISPLAY 1.234043 (1375 4175);
PAINT GREEN (1375 4175);
DISPLAY INVISIBLE (1375 4175);
FORCEPROP 1 LAST PATH I64
J 2
(1702 4300);
DISPLAY 0.872340 (1702 4300);
PAINT GREEN (1702 4300);
DISPLAY INVISIBLE (1702 4300);
FORCEADD TAP..6
(200 4700);
FORCEPROP 3 LASTPIN (250 4700) SIG_NAME M_D_MA<16>
J 0
(260 4710);
DISPLAY 0.659574 (260 4710);
PAINT MONO (260 4710);
DISPLAY INVISIBLE (260 4710);
FORCEPROP 1 LASTPIN (250 4700) BN 16
J 0
(200 4710);
DISPLAY 0.617021 (200 4710);
PAINT PINK (200 4710);
FORCEPROP 2 LAST CDS_LIB mstr_standard
J 2
(200 4700);
DISPLAY 0.787234 (200 4700);
PAINT MONO (200 4700);
DISPLAY INVISIBLE (200 4700);
FORCEPROP 1 LAST BODY_TYPE PLUMBING
J 0
(200 4650);
DISPLAY 1.234043 (200 4650);
PAINT GREEN (200 4650);
DISPLAY INVISIBLE (200 4650);
FORCEPROP 1 LAST HDL_TAP TRUE
J 0
(525 4575);
DISPLAY 1.234043 (525 4575);
PAINT GREEN (525 4575);
DISPLAY INVISIBLE (525 4575);
FORCEPROP 1 LAST PATH I65
J 0
(198 4700);
DISPLAY 0.872340 (198 4700);
PAINT GREEN (198 4700);
DISPLAY INVISIBLE (198 4700);
FORCEADD TAP..6
(200 4750);
FORCEPROP 3 LASTPIN (250 4750) SIG_NAME M_D_MA<17>
J 0
(260 4760);
DISPLAY 0.659574 (260 4760);
PAINT MONO (260 4760);
DISPLAY INVISIBLE (260 4760);
FORCEPROP 1 LASTPIN (250 4750) BN 17
J 0
(200 4760);
DISPLAY 0.617021 (200 4760);
PAINT PINK (200 4760);
FORCEPROP 2 LAST CDS_LIB mstr_standard
J 0
(200 4750);
DISPLAY 0.787234 (200 4750);
PAINT MONO (200 4750);
DISPLAY INVISIBLE (200 4750);
FORCEPROP 1 LAST BODY_TYPE PLUMBING
J 0
(200 4700);
DISPLAY 1.234043 (200 4700);
PAINT GREEN (200 4700);
DISPLAY INVISIBLE (200 4700);
FORCEPROP 1 LAST HDL_TAP TRUE
J 0
(525 4625);
DISPLAY 1.234043 (525 4625);
PAINT GREEN (525 4625);
DISPLAY INVISIBLE (525 4625);
FORCEPROP 1 LAST PATH I66
J 0
(198 4750);
DISPLAY 0.872340 (198 4750);
PAINT GREEN (198 4750);
DISPLAY INVISIBLE (198 4750);
FORCEADD TAP..6
(200 4650);
FORCEPROP 3 LASTPIN (250 4650) SIG_NAME M_D_MA<15>
J 0
(260 4660);
DISPLAY 0.659574 (260 4660);
PAINT MONO (260 4660);
DISPLAY INVISIBLE (260 4660);
FORCEPROP 1 LASTPIN (250 4650) BN 15
J 0
(200 4660);
DISPLAY 0.617021 (200 4660);
PAINT PINK (200 4660);
FORCEPROP 2 LAST CDS_LIB mstr_standard
J 2
(200 4650);
DISPLAY 0.787234 (200 4650);
PAINT MONO (200 4650);
DISPLAY INVISIBLE (200 4650);
FORCEPROP 1 LAST BODY_TYPE PLUMBING
J 0
(200 4600);
DISPLAY 1.234043 (200 4600);
PAINT GREEN (200 4600);
DISPLAY INVISIBLE (200 4600);
FORCEPROP 1 LAST HDL_TAP TRUE
J 0
(525 4525);
DISPLAY 1.234043 (525 4525);
PAINT GREEN (525 4525);
DISPLAY INVISIBLE (525 4525);
FORCEPROP 1 LAST PATH I67
J 0
(198 4650);
DISPLAY 0.872340 (198 4650);
PAINT GREEN (198 4650);
DISPLAY INVISIBLE (198 4650);
FORCEADD TAP..6
(200 4600);
FORCEPROP 3 LASTPIN (250 4600) SIG_NAME M_D_MA<14>
J 0
(260 4610);
DISPLAY 0.659574 (260 4610);
PAINT MONO (260 4610);
DISPLAY INVISIBLE (260 4610);
FORCEPROP 1 LASTPIN (250 4600) BN 14
J 0
(200 4610);
DISPLAY 0.617021 (200 4610);
PAINT PINK (200 4610);
FORCEPROP 2 LAST CDS_LIB mstr_standard
J 2
(200 4600);
DISPLAY 0.787234 (200 4600);
PAINT MONO (200 4600);
DISPLAY INVISIBLE (200 4600);
FORCEPROP 1 LAST BODY_TYPE PLUMBING
J 0
(200 4550);
DISPLAY 1.234043 (200 4550);
PAINT GREEN (200 4550);
DISPLAY INVISIBLE (200 4550);
FORCEPROP 1 LAST HDL_TAP TRUE
J 0
(525 4475);
DISPLAY 1.234043 (525 4475);
PAINT GREEN (525 4475);
DISPLAY INVISIBLE (525 4475);
FORCEPROP 1 LAST PATH I68
J 0
(198 4600);
DISPLAY 0.872340 (198 4600);
PAINT GREEN (198 4600);
DISPLAY INVISIBLE (198 4600);
FORCEADD TAP..6
(200 4550);
FORCEPROP 3 LASTPIN (250 4550) SIG_NAME M_D_MA<13>
J 0
(260 4560);
DISPLAY 0.659574 (260 4560);
PAINT MONO (260 4560);
DISPLAY INVISIBLE (260 4560);
FORCEPROP 1 LASTPIN (250 4550) BN 13
J 0
(200 4560);
DISPLAY 0.617021 (200 4560);
PAINT PINK (200 4560);
FORCEPROP 2 LAST CDS_LIB mstr_standard
J 2
(200 4550);
DISPLAY 0.787234 (200 4550);
PAINT MONO (200 4550);
DISPLAY INVISIBLE (200 4550);
FORCEPROP 1 LAST BODY_TYPE PLUMBING
J 0
(200 4500);
DISPLAY 1.234043 (200 4500);
PAINT GREEN (200 4500);
DISPLAY INVISIBLE (200 4500);
FORCEPROP 1 LAST HDL_TAP TRUE
J 0
(525 4425);
DISPLAY 1.234043 (525 4425);
PAINT GREEN (525 4425);
DISPLAY INVISIBLE (525 4425);
FORCEPROP 1 LAST PATH I69
J 0
(198 4550);
DISPLAY 0.872340 (198 4550);
PAINT GREEN (198 4550);
DISPLAY INVISIBLE (198 4550);
FORCEADD TAP..6
R 2
(4100 4600);
FORCEPROP 3 LASTPIN (4050 4600) SIG_NAME M_D_DQS_DP<15>
J 0
(4060 4610);
DISPLAY 0.659574 (4060 4610);
PAINT MONO (4060 4610);
DISPLAY INVISIBLE (4060 4610);
FORCEPROP 1 LASTPIN (4050 4600) BN 15
J 2
(4100 4610);
DISPLAY 0.617021 (4100 4610);
PAINT PINK (4100 4610);
FORCEPROP 2 LAST CDS_LIB mstr_standard
J 0
(4100 4600);
DISPLAY 0.787234 (4100 4600);
PAINT MONO (4100 4600);
DISPLAY INVISIBLE (4100 4600);
FORCEPROP 1 LAST BODY_TYPE PLUMBING
J 2
(4100 4550);
DISPLAY 1.234043 (4100 4550);
PAINT GREEN (4100 4550);
DISPLAY INVISIBLE (4100 4550);
FORCEPROP 1 LAST HDL_TAP TRUE
J 2
(3775 4475);
DISPLAY 1.234043 (3775 4475);
PAINT GREEN (3775 4475);
DISPLAY INVISIBLE (3775 4475);
FORCEPROP 1 LAST PATH I7
J 2
(4102 4600);
DISPLAY 0.872340 (4102 4600);
PAINT GREEN (4102 4600);
DISPLAY INVISIBLE (4102 4600);
FORCEADD TAP..6
(200 4500);
FORCEPROP 3 LASTPIN (250 4500) SIG_NAME M_D_MA<12>
J 0
(260 4510);
DISPLAY 0.659574 (260 4510);
PAINT MONO (260 4510);
DISPLAY INVISIBLE (260 4510);
FORCEPROP 1 LASTPIN (250 4500) BN 12
J 0
(200 4510);
DISPLAY 0.617021 (200 4510);
PAINT PINK (200 4510);
FORCEPROP 2 LAST CDS_LIB mstr_standard
J 2
(200 4500);
DISPLAY 0.787234 (200 4500);
PAINT MONO (200 4500);
DISPLAY INVISIBLE (200 4500);
FORCEPROP 1 LAST BODY_TYPE PLUMBING
J 0
(200 4450);
DISPLAY 1.234043 (200 4450);
PAINT GREEN (200 4450);
DISPLAY INVISIBLE (200 4450);
FORCEPROP 1 LAST HDL_TAP TRUE
J 0
(525 4375);
DISPLAY 1.234043 (525 4375);
PAINT GREEN (525 4375);
DISPLAY INVISIBLE (525 4375);
FORCEPROP 1 LAST PATH I70
J 0
(198 4500);
DISPLAY 0.872340 (198 4500);
PAINT GREEN (198 4500);
DISPLAY INVISIBLE (198 4500);
FORCEADD TAP..6
(200 4450);
FORCEPROP 3 LASTPIN (250 4450) SIG_NAME M_D_MA<11>
J 0
(260 4460);
DISPLAY 0.659574 (260 4460);
PAINT MONO (260 4460);
DISPLAY INVISIBLE (260 4460);
FORCEPROP 1 LASTPIN (250 4450) BN 11
J 0
(200 4460);
DISPLAY 0.617021 (200 4460);
PAINT PINK (200 4460);
FORCEPROP 2 LAST CDS_LIB mstr_standard
J 2
(200 4450);
DISPLAY 0.787234 (200 4450);
PAINT MONO (200 4450);
DISPLAY INVISIBLE (200 4450);
FORCEPROP 1 LAST BODY_TYPE PLUMBING
J 0
(200 4400);
DISPLAY 1.234043 (200 4400);
PAINT GREEN (200 4400);
DISPLAY INVISIBLE (200 4400);
FORCEPROP 1 LAST HDL_TAP TRUE
J 0
(525 4325);
DISPLAY 1.234043 (525 4325);
PAINT GREEN (525 4325);
DISPLAY INVISIBLE (525 4325);
FORCEPROP 1 LAST PATH I71
J 0
(198 4450);
DISPLAY 0.872340 (198 4450);
PAINT GREEN (198 4450);
DISPLAY INVISIBLE (198 4450);
FORCEADD TAP..6
(200 4400);
FORCEPROP 3 LASTPIN (250 4400) SIG_NAME M_D_MA<10>
J 0
(260 4410);
DISPLAY 0.659574 (260 4410);
PAINT MONO (260 4410);
DISPLAY INVISIBLE (260 4410);
FORCEPROP 1 LASTPIN (250 4400) BN 10
J 0
(200 4410);
DISPLAY 0.617021 (200 4410);
PAINT PINK (200 4410);
FORCEPROP 2 LAST CDS_LIB mstr_standard
J 2
(200 4400);
DISPLAY 0.787234 (200 4400);
PAINT MONO (200 4400);
DISPLAY INVISIBLE (200 4400);
FORCEPROP 1 LAST BODY_TYPE PLUMBING
J 0
(200 4350);
DISPLAY 1.234043 (200 4350);
PAINT GREEN (200 4350);
DISPLAY INVISIBLE (200 4350);
FORCEPROP 1 LAST HDL_TAP TRUE
J 0
(525 4275);
DISPLAY 1.234043 (525 4275);
PAINT GREEN (525 4275);
DISPLAY INVISIBLE (525 4275);
FORCEPROP 1 LAST PATH I72
J 0
(198 4400);
DISPLAY 0.872340 (198 4400);
PAINT GREEN (198 4400);
DISPLAY INVISIBLE (198 4400);
FORCEADD TAP..6
(200 4350);
FORCEPROP 3 LASTPIN (250 4350) SIG_NAME M_D_MA<9>
J 0
(260 4360);
DISPLAY 0.659574 (260 4360);
PAINT MONO (260 4360);
DISPLAY INVISIBLE (260 4360);
FORCEPROP 1 LASTPIN (250 4350) BN 9
J 0
(200 4360);
DISPLAY 0.617021 (200 4360);
PAINT PINK (200 4360);
FORCEPROP 2 LAST CDS_LIB mstr_standard
J 2
(200 4350);
DISPLAY 0.787234 (200 4350);
PAINT MONO (200 4350);
DISPLAY INVISIBLE (200 4350);
FORCEPROP 1 LAST BODY_TYPE PLUMBING
J 0
(200 4300);
DISPLAY 1.234043 (200 4300);
PAINT GREEN (200 4300);
DISPLAY INVISIBLE (200 4300);
FORCEPROP 1 LAST HDL_TAP TRUE
J 0
(525 4225);
DISPLAY 1.234043 (525 4225);
PAINT GREEN (525 4225);
DISPLAY INVISIBLE (525 4225);
FORCEPROP 1 LAST PATH I73
J 0
(198 4350);
DISPLAY 0.872340 (198 4350);
PAINT GREEN (198 4350);
DISPLAY INVISIBLE (198 4350);
FORCEADD TAP..6
(200 4300);
FORCEPROP 3 LASTPIN (250 4300) SIG_NAME M_D_MA<8>
J 0
(260 4310);
DISPLAY 0.659574 (260 4310);
PAINT MONO (260 4310);
DISPLAY INVISIBLE (260 4310);
FORCEPROP 1 LASTPIN (250 4300) BN 8
J 0
(200 4310);
DISPLAY 0.617021 (200 4310);
PAINT PINK (200 4310);
FORCEPROP 2 LAST CDS_LIB mstr_standard
J 2
(200 4300);
DISPLAY 0.787234 (200 4300);
PAINT MONO (200 4300);
DISPLAY INVISIBLE (200 4300);
FORCEPROP 1 LAST BODY_TYPE PLUMBING
J 0
(200 4250);
DISPLAY 1.234043 (200 4250);
PAINT GREEN (200 4250);
DISPLAY INVISIBLE (200 4250);
FORCEPROP 1 LAST HDL_TAP TRUE
J 0
(525 4175);
DISPLAY 1.234043 (525 4175);
PAINT GREEN (525 4175);
DISPLAY INVISIBLE (525 4175);
FORCEPROP 1 LAST PATH I74
J 0
(198 4300);
DISPLAY 0.872340 (198 4300);
PAINT GREEN (198 4300);
DISPLAY INVISIBLE (198 4300);
FORCEADD TAP..6
(200 4250);
FORCEPROP 3 LASTPIN (250 4250) SIG_NAME M_D_MA<7>
J 0
(260 4260);
DISPLAY 0.659574 (260 4260);
PAINT MONO (260 4260);
DISPLAY INVISIBLE (260 4260);
FORCEPROP 1 LASTPIN (250 4250) BN 7
J 0
(200 4260);
DISPLAY 0.617021 (200 4260);
PAINT PINK (200 4260);
FORCEPROP 2 LAST CDS_LIB mstr_standard
J 2
(200 4250);
DISPLAY 0.787234 (200 4250);
PAINT MONO (200 4250);
DISPLAY INVISIBLE (200 4250);
FORCEPROP 1 LAST BODY_TYPE PLUMBING
J 0
(200 4200);
DISPLAY 1.234043 (200 4200);
PAINT GREEN (200 4200);
DISPLAY INVISIBLE (200 4200);
FORCEPROP 1 LAST HDL_TAP TRUE
J 0
(525 4125);
DISPLAY 1.234043 (525 4125);
PAINT GREEN (525 4125);
DISPLAY INVISIBLE (525 4125);
FORCEPROP 1 LAST PATH I75
J 0
(198 4250);
DISPLAY 0.872340 (198 4250);
PAINT GREEN (198 4250);
DISPLAY INVISIBLE (198 4250);
FORCEADD TAP..6
(200 4200);
FORCEPROP 3 LASTPIN (250 4200) SIG_NAME M_D_MA<6>
J 0
(260 4210);
DISPLAY 0.659574 (260 4210);
PAINT MONO (260 4210);
DISPLAY INVISIBLE (260 4210);
FORCEPROP 1 LASTPIN (250 4200) BN 6
J 0
(200 4210);
DISPLAY 0.617021 (200 4210);
PAINT PINK (200 4210);
FORCEPROP 2 LAST CDS_LIB mstr_standard
J 2
(200 4200);
DISPLAY 0.787234 (200 4200);
PAINT MONO (200 4200);
DISPLAY INVISIBLE (200 4200);
FORCEPROP 1 LAST BODY_TYPE PLUMBING
J 0
(200 4150);
DISPLAY 1.234043 (200 4150);
PAINT GREEN (200 4150);
DISPLAY INVISIBLE (200 4150);
FORCEPROP 1 LAST HDL_TAP TRUE
J 0
(525 4075);
DISPLAY 1.234043 (525 4075);
PAINT GREEN (525 4075);
DISPLAY INVISIBLE (525 4075);
FORCEPROP 1 LAST PATH I76
J 0
(198 4200);
DISPLAY 0.872340 (198 4200);
PAINT GREEN (198 4200);
DISPLAY INVISIBLE (198 4200);
FORCEADD TAP..6
(200 4150);
FORCEPROP 3 LASTPIN (250 4150) SIG_NAME M_D_MA<5>
J 0
(260 4160);
DISPLAY 0.659574 (260 4160);
PAINT MONO (260 4160);
DISPLAY INVISIBLE (260 4160);
FORCEPROP 1 LASTPIN (250 4150) BN 5
J 0
(200 4160);
DISPLAY 0.617021 (200 4160);
PAINT PINK (200 4160);
FORCEPROP 2 LAST CDS_LIB mstr_standard
J 2
(200 4150);
DISPLAY 0.787234 (200 4150);
PAINT MONO (200 4150);
DISPLAY INVISIBLE (200 4150);
FORCEPROP 1 LAST BODY_TYPE PLUMBING
J 0
(200 4100);
DISPLAY 1.234043 (200 4100);
PAINT GREEN (200 4100);
DISPLAY INVISIBLE (200 4100);
FORCEPROP 1 LAST HDL_TAP TRUE
J 0
(525 4025);
DISPLAY 1.234043 (525 4025);
PAINT GREEN (525 4025);
DISPLAY INVISIBLE (525 4025);
FORCEPROP 1 LAST PATH I77
J 0
(198 4150);
DISPLAY 0.872340 (198 4150);
PAINT GREEN (198 4150);
DISPLAY INVISIBLE (198 4150);
FORCEADD TAP..6
(200 4100);
FORCEPROP 3 LASTPIN (250 4100) SIG_NAME M_D_MA<4>
J 0
(260 4110);
DISPLAY 0.659574 (260 4110);
PAINT MONO (260 4110);
DISPLAY INVISIBLE (260 4110);
FORCEPROP 1 LASTPIN (250 4100) BN 4
J 0
(200 4110);
DISPLAY 0.617021 (200 4110);
PAINT PINK (200 4110);
FORCEPROP 2 LAST CDS_LIB mstr_standard
J 2
(200 4100);
DISPLAY 0.787234 (200 4100);
PAINT MONO (200 4100);
DISPLAY INVISIBLE (200 4100);
FORCEPROP 1 LAST BODY_TYPE PLUMBING
J 0
(200 4050);
DISPLAY 1.234043 (200 4050);
PAINT GREEN (200 4050);
DISPLAY INVISIBLE (200 4050);
FORCEPROP 1 LAST HDL_TAP TRUE
J 0
(525 3975);
DISPLAY 1.234043 (525 3975);
PAINT GREEN (525 3975);
DISPLAY INVISIBLE (525 3975);
FORCEPROP 1 LAST PATH I78
J 0
(198 4100);
DISPLAY 0.872340 (198 4100);
PAINT GREEN (198 4100);
DISPLAY INVISIBLE (198 4100);
FORCEADD OFFPAGE..1
(-550 4800);
FORCEPROP 2 LAST $XR1 49 
J 0
(-861 4800);
DISPLAY 0.638298 (-861 4800);
PAINT MONO (-861 4800);
FORCEPROP 2 LAST $XR0 26 
J 0
(-771 4800);
DISPLAY 0.638298 (-771 4800);
PAINT MONO (-771 4800);
FORCEPROP 2 LAST CDS_LIB mstr_standard
J 0
(-550 4800);
DISPLAY 0.787234 (-550 4800);
PAINT MONO (-550 4800);
DISPLAY INVISIBLE (-550 4800);
FORCEPROP 1 LAST OFFPAGE TRUE
J 0
(-225 4675);
DISPLAY 0.936170 (-225 4675);
PAINT GREEN (-225 4675);
DISPLAY INVISIBLE (-225 4675);
FORCEPROP 1 LAST COMMENT_BODY TRUE
J 0
(-425 4700);
DISPLAY 0.936170 (-425 4700);
PAINT GREEN (-425 4700);
DISPLAY INVISIBLE (-425 4700);
FORCEPROP 2 LAST PATH I79
J 0
(-750 4850);
DISPLAY 1.021277 (-750 4850);
PAINT ORANGE (-750 4850);
DISPLAY INVISIBLE (-750 4850);
FORCEADD TAP..6
R 2
(4100 4700);
FORCEPROP 3 LASTPIN (4050 4700) SIG_NAME M_D_DQS_DP<16>
J 0
(4060 4710);
DISPLAY 0.659574 (4060 4710);
PAINT MONO (4060 4710);
DISPLAY INVISIBLE (4060 4710);
FORCEPROP 1 LASTPIN (4050 4700) BN 16
J 2
(4100 4710);
DISPLAY 0.617021 (4100 4710);
PAINT PINK (4100 4710);
FORCEPROP 2 LAST CDS_LIB mstr_standard
J 0
(4100 4700);
DISPLAY 0.787234 (4100 4700);
PAINT MONO (4100 4700);
DISPLAY INVISIBLE (4100 4700);
FORCEPROP 1 LAST BODY_TYPE PLUMBING
J 2
(4100 4650);
DISPLAY 1.234043 (4100 4650);
PAINT GREEN (4100 4650);
DISPLAY INVISIBLE (4100 4650);
FORCEPROP 1 LAST HDL_TAP TRUE
J 2
(3775 4575);
DISPLAY 1.234043 (3775 4575);
PAINT GREEN (3775 4575);
DISPLAY INVISIBLE (3775 4575);
FORCEPROP 1 LAST PATH I8
J 2
(4102 4700);
DISPLAY 0.872340 (4102 4700);
PAINT GREEN (4102 4700);
DISPLAY INVISIBLE (4102 4700);
FORCEADD TAP..6
R 2
(1700 3950);
FORCEPROP 3 LASTPIN (1650 3950) SIG_NAME M_D_DQ<47>
J 0
(1660 3960);
DISPLAY 0.659574 (1660 3960);
PAINT MONO (1660 3960);
DISPLAY INVISIBLE (1660 3960);
FORCEPROP 1 LASTPIN (1650 3950) BN 47
J 2
(1700 3960);
DISPLAY 0.617021 (1700 3960);
PAINT PINK (1700 3960);
FORCEPROP 2 LAST CDS_LIB mstr_standard
J 2
(1700 3950);
DISPLAY 0.787234 (1700 3950);
PAINT MONO (1700 3950);
DISPLAY INVISIBLE (1700 3950);
FORCEPROP 1 LAST BODY_TYPE PLUMBING
J 2
(1700 3900);
DISPLAY 1.234043 (1700 3900);
PAINT GREEN (1700 3900);
DISPLAY INVISIBLE (1700 3900);
FORCEPROP 1 LAST HDL_TAP TRUE
J 2
(1375 3825);
DISPLAY 1.234043 (1375 3825);
PAINT GREEN (1375 3825);
DISPLAY INVISIBLE (1375 3825);
FORCEPROP 1 LAST PATH I80
J 2
(1702 3950);
DISPLAY 0.872340 (1702 3950);
PAINT GREEN (1702 3950);
DISPLAY INVISIBLE (1702 3950);
FORCEADD TAP..6
R 2
(1700 3850);
FORCEPROP 3 LASTPIN (1650 3850) SIG_NAME M_D_DQ<45>
J 0
(1660 3860);
DISPLAY 0.659574 (1660 3860);
PAINT MONO (1660 3860);
DISPLAY INVISIBLE (1660 3860);
FORCEPROP 1 LASTPIN (1650 3850) BN 45
J 2
(1700 3860);
DISPLAY 0.617021 (1700 3860);
PAINT PINK (1700 3860);
FORCEPROP 2 LAST CDS_LIB mstr_standard
J 2
(1700 3850);
DISPLAY 0.787234 (1700 3850);
PAINT MONO (1700 3850);
DISPLAY INVISIBLE (1700 3850);
FORCEPROP 1 LAST BODY_TYPE PLUMBING
J 2
(1700 3800);
DISPLAY 1.234043 (1700 3800);
PAINT GREEN (1700 3800);
DISPLAY INVISIBLE (1700 3800);
FORCEPROP 1 LAST HDL_TAP TRUE
J 2
(1375 3725);
DISPLAY 1.234043 (1375 3725);
PAINT GREEN (1375 3725);
DISPLAY INVISIBLE (1375 3725);
FORCEPROP 1 LAST PATH I81
J 2
(1702 3850);
DISPLAY 0.872340 (1702 3850);
PAINT GREEN (1702 3850);
DISPLAY INVISIBLE (1702 3850);
FORCEADD TAP..6
R 2
(1700 4000);
FORCEPROP 3 LASTPIN (1650 4000) SIG_NAME M_D_DQ<48>
J 0
(1660 4010);
DISPLAY 0.659574 (1660 4010);
PAINT MONO (1660 4010);
DISPLAY INVISIBLE (1660 4010);
FORCEPROP 1 LASTPIN (1650 4000) BN 48
J 2
(1700 4010);
DISPLAY 0.617021 (1700 4010);
PAINT PINK (1700 4010);
FORCEPROP 2 LAST CDS_LIB mstr_standard
J 2
(1700 4000);
DISPLAY 0.787234 (1700 4000);
PAINT MONO (1700 4000);
DISPLAY INVISIBLE (1700 4000);
FORCEPROP 1 LAST BODY_TYPE PLUMBING
J 2
(1700 3950);
DISPLAY 1.234043 (1700 3950);
PAINT GREEN (1700 3950);
DISPLAY INVISIBLE (1700 3950);
FORCEPROP 1 LAST HDL_TAP TRUE
J 2
(1375 3875);
DISPLAY 1.234043 (1375 3875);
PAINT GREEN (1375 3875);
DISPLAY INVISIBLE (1375 3875);
FORCEPROP 1 LAST PATH I82
J 2
(1702 4000);
DISPLAY 0.872340 (1702 4000);
PAINT GREEN (1702 4000);
DISPLAY INVISIBLE (1702 4000);
FORCEADD TAP..6
R 2
(1700 4050);
FORCEPROP 3 LASTPIN (1650 4050) SIG_NAME M_D_DQ<49>
J 0
(1660 4060);
DISPLAY 0.659574 (1660 4060);
PAINT MONO (1660 4060);
DISPLAY INVISIBLE (1660 4060);
FORCEPROP 1 LASTPIN (1650 4050) BN 49
J 2
(1700 4060);
DISPLAY 0.617021 (1700 4060);
PAINT PINK (1700 4060);
FORCEPROP 2 LAST CDS_LIB mstr_standard
J 2
(1700 4050);
DISPLAY 0.787234 (1700 4050);
PAINT MONO (1700 4050);
DISPLAY INVISIBLE (1700 4050);
FORCEPROP 1 LAST BODY_TYPE PLUMBING
J 2
(1700 4000);
DISPLAY 1.234043 (1700 4000);
PAINT GREEN (1700 4000);
DISPLAY INVISIBLE (1700 4000);
FORCEPROP 1 LAST HDL_TAP TRUE
J 2
(1375 3925);
DISPLAY 1.234043 (1375 3925);
PAINT GREEN (1375 3925);
DISPLAY INVISIBLE (1375 3925);
FORCEPROP 1 LAST PATH I83
J 2
(1702 4050);
DISPLAY 0.872340 (1702 4050);
PAINT GREEN (1702 4050);
DISPLAY INVISIBLE (1702 4050);
FORCEADD TAP..6
R 2
(1700 3900);
FORCEPROP 3 LASTPIN (1650 3900) SIG_NAME M_D_DQ<46>
J 0
(1660 3910);
DISPLAY 0.659574 (1660 3910);
PAINT MONO (1660 3910);
DISPLAY INVISIBLE (1660 3910);
FORCEPROP 1 LASTPIN (1650 3900) BN 46
J 2
(1700 3910);
DISPLAY 0.617021 (1700 3910);
PAINT PINK (1700 3910);
FORCEPROP 2 LAST CDS_LIB mstr_standard
J 2
(1700 3900);
DISPLAY 0.787234 (1700 3900);
PAINT MONO (1700 3900);
DISPLAY INVISIBLE (1700 3900);
FORCEPROP 1 LAST BODY_TYPE PLUMBING
J 2
(1700 3850);
DISPLAY 1.234043 (1700 3850);
PAINT GREEN (1700 3850);
DISPLAY INVISIBLE (1700 3850);
FORCEPROP 1 LAST HDL_TAP TRUE
J 2
(1375 3775);
DISPLAY 1.234043 (1375 3775);
PAINT GREEN (1375 3775);
DISPLAY INVISIBLE (1375 3775);
FORCEPROP 1 LAST PATH I84
J 2
(1702 3900);
DISPLAY 0.872340 (1702 3900);
PAINT GREEN (1702 3900);
DISPLAY INVISIBLE (1702 3900);
FORCEADD TAP..6
R 2
(1700 3700);
FORCEPROP 3 LASTPIN (1650 3700) SIG_NAME M_D_DQ<42>
J 0
(1660 3710);
DISPLAY 0.659574 (1660 3710);
PAINT MONO (1660 3710);
DISPLAY INVISIBLE (1660 3710);
FORCEPROP 1 LASTPIN (1650 3700) BN 42
J 2
(1700 3710);
DISPLAY 0.617021 (1700 3710);
PAINT PINK (1700 3710);
FORCEPROP 2 LAST CDS_LIB mstr_standard
J 2
(1700 3700);
DISPLAY 0.787234 (1700 3700);
PAINT MONO (1700 3700);
DISPLAY INVISIBLE (1700 3700);
FORCEPROP 1 LAST BODY_TYPE PLUMBING
J 2
(1700 3650);
DISPLAY 1.234043 (1700 3650);
PAINT GREEN (1700 3650);
DISPLAY INVISIBLE (1700 3650);
FORCEPROP 1 LAST HDL_TAP TRUE
J 2
(1375 3575);
DISPLAY 1.234043 (1375 3575);
PAINT GREEN (1375 3575);
DISPLAY INVISIBLE (1375 3575);
FORCEPROP 1 LAST PATH I85
J 2
(1702 3700);
DISPLAY 0.872340 (1702 3700);
PAINT GREEN (1702 3700);
DISPLAY INVISIBLE (1702 3700);
FORCEADD TAP..6
R 2
(1700 3750);
FORCEPROP 3 LASTPIN (1650 3750) SIG_NAME M_D_DQ<43>
J 0
(1660 3760);
DISPLAY 0.659574 (1660 3760);
PAINT MONO (1660 3760);
DISPLAY INVISIBLE (1660 3760);
FORCEPROP 1 LASTPIN (1650 3750) BN 43
J 2
(1700 3760);
DISPLAY 0.617021 (1700 3760);
PAINT PINK (1700 3760);
FORCEPROP 2 LAST CDS_LIB mstr_standard
J 2
(1700 3750);
DISPLAY 0.787234 (1700 3750);
PAINT MONO (1700 3750);
DISPLAY INVISIBLE (1700 3750);
FORCEPROP 1 LAST BODY_TYPE PLUMBING
J 2
(1700 3700);
DISPLAY 1.234043 (1700 3700);
PAINT GREEN (1700 3700);
DISPLAY INVISIBLE (1700 3700);
FORCEPROP 1 LAST HDL_TAP TRUE
J 2
(1375 3625);
DISPLAY 1.234043 (1375 3625);
PAINT GREEN (1375 3625);
DISPLAY INVISIBLE (1375 3625);
FORCEPROP 1 LAST PATH I86
J 2
(1702 3750);
DISPLAY 0.872340 (1702 3750);
PAINT GREEN (1702 3750);
DISPLAY INVISIBLE (1702 3750);
FORCEADD TAP..6
R 2
(1700 3800);
FORCEPROP 3 LASTPIN (1650 3800) SIG_NAME M_D_DQ<44>
J 0
(1660 3810);
DISPLAY 0.659574 (1660 3810);
PAINT MONO (1660 3810);
DISPLAY INVISIBLE (1660 3810);
FORCEPROP 1 LASTPIN (1650 3800) BN 44
J 2
(1700 3810);
DISPLAY 0.617021 (1700 3810);
PAINT PINK (1700 3810);
FORCEPROP 2 LAST CDS_LIB mstr_standard
J 2
(1700 3800);
DISPLAY 0.787234 (1700 3800);
PAINT MONO (1700 3800);
DISPLAY INVISIBLE (1700 3800);
FORCEPROP 1 LAST BODY_TYPE PLUMBING
J 2
(1700 3750);
DISPLAY 1.234043 (1700 3750);
PAINT GREEN (1700 3750);
DISPLAY INVISIBLE (1700 3750);
FORCEPROP 1 LAST HDL_TAP TRUE
J 2
(1375 3675);
DISPLAY 1.234043 (1375 3675);
PAINT GREEN (1375 3675);
DISPLAY INVISIBLE (1375 3675);
FORCEPROP 1 LAST PATH I87
J 2
(1702 3800);
DISPLAY 0.872340 (1702 3800);
PAINT GREEN (1702 3800);
DISPLAY INVISIBLE (1702 3800);
FORCEADD TAP..6
R 2
(1700 3650);
FORCEPROP 3 LASTPIN (1650 3650) SIG_NAME M_D_DQ<41>
J 0
(1660 3660);
DISPLAY 0.659574 (1660 3660);
PAINT MONO (1660 3660);
DISPLAY INVISIBLE (1660 3660);
FORCEPROP 1 LASTPIN (1650 3650) BN 41
J 2
(1700 3660);
DISPLAY 0.617021 (1700 3660);
PAINT PINK (1700 3660);
FORCEPROP 2 LAST CDS_LIB mstr_standard
J 2
(1700 3650);
DISPLAY 0.787234 (1700 3650);
PAINT MONO (1700 3650);
DISPLAY INVISIBLE (1700 3650);
FORCEPROP 1 LAST BODY_TYPE PLUMBING
J 2
(1700 3600);
DISPLAY 1.234043 (1700 3600);
PAINT GREEN (1700 3600);
DISPLAY INVISIBLE (1700 3600);
FORCEPROP 1 LAST HDL_TAP TRUE
J 2
(1375 3525);
DISPLAY 1.234043 (1375 3525);
PAINT GREEN (1375 3525);
DISPLAY INVISIBLE (1375 3525);
FORCEPROP 1 LAST PATH I88
J 2
(1702 3650);
DISPLAY 0.872340 (1702 3650);
PAINT GREEN (1702 3650);
DISPLAY INVISIBLE (1702 3650);
FORCEADD TAP..6
R 2
(1700 3600);
FORCEPROP 3 LASTPIN (1650 3600) SIG_NAME M_D_DQ<40>
J 0
(1660 3610);
DISPLAY 0.659574 (1660 3610);
PAINT MONO (1660 3610);
DISPLAY INVISIBLE (1660 3610);
FORCEPROP 1 LASTPIN (1650 3600) BN 40
J 2
(1700 3610);
DISPLAY 0.617021 (1700 3610);
PAINT PINK (1700 3610);
FORCEPROP 2 LAST CDS_LIB mstr_standard
J 2
(1700 3600);
DISPLAY 0.787234 (1700 3600);
PAINT MONO (1700 3600);
DISPLAY INVISIBLE (1700 3600);
FORCEPROP 1 LAST BODY_TYPE PLUMBING
J 2
(1700 3550);
DISPLAY 1.234043 (1700 3550);
PAINT GREEN (1700 3550);
DISPLAY INVISIBLE (1700 3550);
FORCEPROP 1 LAST HDL_TAP TRUE
J 2
(1375 3475);
DISPLAY 1.234043 (1375 3475);
PAINT GREEN (1375 3475);
DISPLAY INVISIBLE (1375 3475);
FORCEPROP 1 LAST PATH I89
J 2
(1702 3600);
DISPLAY 0.872340 (1702 3600);
PAINT GREEN (1702 3600);
DISPLAY INVISIBLE (1702 3600);
FORCEADD TAP..6
R 2
(4350 4550);
FORCEPROP 3 LASTPIN (4300 4550) SIG_NAME M_D_DQS_DN<15>
J 0
(4310 4560);
DISPLAY 0.659574 (4310 4560);
PAINT MONO (4310 4560);
DISPLAY INVISIBLE (4310 4560);
FORCEPROP 1 LASTPIN (4300 4550) BN 15
J 2
(4350 4560);
DISPLAY 0.617021 (4350 4560);
PAINT PINK (4350 4560);
FORCEPROP 2 LAST CDS_LIB mstr_standard
J 0
(4350 4550);
DISPLAY 0.787234 (4350 4550);
PAINT MONO (4350 4550);
DISPLAY INVISIBLE (4350 4550);
FORCEPROP 1 LAST BODY_TYPE PLUMBING
J 2
(4350 4500);
DISPLAY 1.234043 (4350 4500);
PAINT GREEN (4350 4500);
DISPLAY INVISIBLE (4350 4500);
FORCEPROP 1 LAST HDL_TAP TRUE
J 2
(4025 4425);
DISPLAY 1.234043 (4025 4425);
PAINT GREEN (4025 4425);
DISPLAY INVISIBLE (4025 4425);
FORCEPROP 1 LAST PATH I9
J 2
(4352 4550);
DISPLAY 0.872340 (4352 4550);
PAINT GREEN (4352 4550);
DISPLAY INVISIBLE (4352 4550);
FORCEADD TAP..6
R 2
(1700 3350);
FORCEPROP 3 LASTPIN (1650 3350) SIG_NAME M_D_DQ<35>
J 0
(1660 3360);
DISPLAY 0.659574 (1660 3360);
PAINT MONO (1660 3360);
DISPLAY INVISIBLE (1660 3360);
FORCEPROP 1 LASTPIN (1650 3350) BN 35
J 2
(1700 3360);
DISPLAY 0.617021 (1700 3360);
PAINT PINK (1700 3360);
FORCEPROP 2 LAST CDS_LIB mstr_standard
J 2
(1700 3350);
DISPLAY 0.787234 (1700 3350);
PAINT MONO (1700 3350);
DISPLAY INVISIBLE (1700 3350);
FORCEPROP 1 LAST BODY_TYPE PLUMBING
J 2
(1700 3300);
DISPLAY 1.234043 (1700 3300);
PAINT GREEN (1700 3300);
DISPLAY INVISIBLE (1700 3300);
FORCEPROP 1 LAST HDL_TAP TRUE
J 2
(1375 3225);
DISPLAY 1.234043 (1375 3225);
PAINT GREEN (1375 3225);
DISPLAY INVISIBLE (1375 3225);
FORCEPROP 1 LAST PATH I90
J 2
(1702 3350);
DISPLAY 0.872340 (1702 3350);
PAINT GREEN (1702 3350);
DISPLAY INVISIBLE (1702 3350);
FORCEADD TAP..6
R 2
(1700 3400);
FORCEPROP 3 LASTPIN (1650 3400) SIG_NAME M_D_DQ<36>
J 0
(1660 3410);
DISPLAY 0.659574 (1660 3410);
PAINT MONO (1660 3410);
DISPLAY INVISIBLE (1660 3410);
FORCEPROP 1 LASTPIN (1650 3400) BN 36
J 2
(1700 3410);
DISPLAY 0.617021 (1700 3410);
PAINT PINK (1700 3410);
FORCEPROP 2 LAST CDS_LIB mstr_standard
J 2
(1700 3400);
DISPLAY 0.787234 (1700 3400);
PAINT MONO (1700 3400);
DISPLAY INVISIBLE (1700 3400);
FORCEPROP 1 LAST BODY_TYPE PLUMBING
J 2
(1700 3350);
DISPLAY 1.234043 (1700 3350);
PAINT GREEN (1700 3350);
DISPLAY INVISIBLE (1700 3350);
FORCEPROP 1 LAST HDL_TAP TRUE
J 2
(1375 3275);
DISPLAY 1.234043 (1375 3275);
PAINT GREEN (1375 3275);
DISPLAY INVISIBLE (1375 3275);
FORCEPROP 1 LAST PATH I91
J 2
(1702 3400);
DISPLAY 0.872340 (1702 3400);
PAINT GREEN (1702 3400);
DISPLAY INVISIBLE (1702 3400);
FORCEADD TAP..6
R 2
(1700 3500);
FORCEPROP 3 LASTPIN (1650 3500) SIG_NAME M_D_DQ<38>
J 0
(1660 3510);
DISPLAY 0.659574 (1660 3510);
PAINT MONO (1660 3510);
DISPLAY INVISIBLE (1660 3510);
FORCEPROP 1 LASTPIN (1650 3500) BN 38
J 2
(1700 3510);
DISPLAY 0.617021 (1700 3510);
PAINT PINK (1700 3510);
FORCEPROP 2 LAST CDS_LIB mstr_standard
J 2
(1700 3500);
DISPLAY 0.787234 (1700 3500);
PAINT MONO (1700 3500);
DISPLAY INVISIBLE (1700 3500);
FORCEPROP 1 LAST BODY_TYPE PLUMBING
J 2
(1700 3450);
DISPLAY 1.234043 (1700 3450);
PAINT GREEN (1700 3450);
DISPLAY INVISIBLE (1700 3450);
FORCEPROP 1 LAST HDL_TAP TRUE
J 2
(1375 3375);
DISPLAY 1.234043 (1375 3375);
PAINT GREEN (1375 3375);
DISPLAY INVISIBLE (1375 3375);
FORCEPROP 1 LAST PATH I92
J 2
(1702 3500);
DISPLAY 0.872340 (1702 3500);
PAINT GREEN (1702 3500);
DISPLAY INVISIBLE (1702 3500);
FORCEADD TAP..6
R 2
(1700 3450);
FORCEPROP 3 LASTPIN (1650 3450) SIG_NAME M_D_DQ<37>
J 0
(1660 3460);
DISPLAY 0.659574 (1660 3460);
PAINT MONO (1660 3460);
DISPLAY INVISIBLE (1660 3460);
FORCEPROP 1 LASTPIN (1650 3450) BN 37
J 2
(1700 3460);
DISPLAY 0.617021 (1700 3460);
PAINT PINK (1700 3460);
FORCEPROP 2 LAST CDS_LIB mstr_standard
J 2
(1700 3450);
DISPLAY 0.787234 (1700 3450);
PAINT MONO (1700 3450);
DISPLAY INVISIBLE (1700 3450);
FORCEPROP 1 LAST BODY_TYPE PLUMBING
J 2
(1700 3400);
DISPLAY 1.234043 (1700 3400);
PAINT GREEN (1700 3400);
DISPLAY INVISIBLE (1700 3400);
FORCEPROP 1 LAST HDL_TAP TRUE
J 2
(1375 3325);
DISPLAY 1.234043 (1375 3325);
PAINT GREEN (1375 3325);
DISPLAY INVISIBLE (1375 3325);
FORCEPROP 1 LAST PATH I93
J 2
(1702 3450);
DISPLAY 0.872340 (1702 3450);
PAINT GREEN (1702 3450);
DISPLAY INVISIBLE (1702 3450);
FORCEADD TAP..6
R 2
(1700 3550);
FORCEPROP 3 LASTPIN (1650 3550) SIG_NAME M_D_DQ<39>
J 0
(1660 3560);
DISPLAY 0.659574 (1660 3560);
PAINT MONO (1660 3560);
DISPLAY INVISIBLE (1660 3560);
FORCEPROP 1 LASTPIN (1650 3550) BN 39
J 2
(1700 3560);
DISPLAY 0.617021 (1700 3560);
PAINT PINK (1700 3560);
FORCEPROP 2 LAST CDS_LIB mstr_standard
J 2
(1700 3550);
DISPLAY 0.787234 (1700 3550);
PAINT MONO (1700 3550);
DISPLAY INVISIBLE (1700 3550);
FORCEPROP 1 LAST BODY_TYPE PLUMBING
J 2
(1700 3500);
DISPLAY 1.234043 (1700 3500);
PAINT GREEN (1700 3500);
DISPLAY INVISIBLE (1700 3500);
FORCEPROP 1 LAST HDL_TAP TRUE
J 2
(1375 3425);
DISPLAY 1.234043 (1375 3425);
PAINT GREEN (1375 3425);
DISPLAY INVISIBLE (1375 3425);
FORCEPROP 1 LAST PATH I94
J 2
(1702 3550);
DISPLAY 0.872340 (1702 3550);
PAINT GREEN (1702 3550);
DISPLAY INVISIBLE (1702 3550);
FORCEADD TAP..6
R 2
(1700 3200);
FORCEPROP 3 LASTPIN (1650 3200) SIG_NAME M_D_DQ<32>
J 0
(1660 3210);
DISPLAY 0.659574 (1660 3210);
PAINT MONO (1660 3210);
DISPLAY INVISIBLE (1660 3210);
FORCEPROP 1 LASTPIN (1650 3200) BN 32
J 2
(1700 3210);
DISPLAY 0.617021 (1700 3210);
PAINT PINK (1700 3210);
FORCEPROP 2 LAST CDS_LIB mstr_standard
J 2
(1700 3200);
DISPLAY 0.787234 (1700 3200);
PAINT MONO (1700 3200);
DISPLAY INVISIBLE (1700 3200);
FORCEPROP 1 LAST BODY_TYPE PLUMBING
J 2
(1700 3150);
DISPLAY 1.234043 (1700 3150);
PAINT GREEN (1700 3150);
DISPLAY INVISIBLE (1700 3150);
FORCEPROP 1 LAST HDL_TAP TRUE
J 2
(1375 3075);
DISPLAY 1.234043 (1375 3075);
PAINT GREEN (1375 3075);
DISPLAY INVISIBLE (1375 3075);
FORCEPROP 1 LAST PATH I95
J 2
(1702 3200);
DISPLAY 0.872340 (1702 3200);
PAINT GREEN (1702 3200);
DISPLAY INVISIBLE (1702 3200);
FORCEADD TAP..6
R 2
(1700 3250);
FORCEPROP 3 LASTPIN (1650 3250) SIG_NAME M_D_DQ<33>
J 0
(1660 3260);
DISPLAY 0.659574 (1660 3260);
PAINT MONO (1660 3260);
DISPLAY INVISIBLE (1660 3260);
FORCEPROP 1 LASTPIN (1650 3250) BN 33
J 2
(1700 3260);
DISPLAY 0.617021 (1700 3260);
PAINT PINK (1700 3260);
FORCEPROP 2 LAST CDS_LIB mstr_standard
J 2
(1700 3250);
DISPLAY 0.787234 (1700 3250);
PAINT MONO (1700 3250);
DISPLAY INVISIBLE (1700 3250);
FORCEPROP 1 LAST BODY_TYPE PLUMBING
J 2
(1700 3200);
DISPLAY 1.234043 (1700 3200);
PAINT GREEN (1700 3200);
DISPLAY INVISIBLE (1700 3200);
FORCEPROP 1 LAST HDL_TAP TRUE
J 2
(1375 3125);
DISPLAY 1.234043 (1375 3125);
PAINT GREEN (1375 3125);
DISPLAY INVISIBLE (1375 3125);
FORCEPROP 1 LAST PATH I96
J 2
(1702 3250);
DISPLAY 0.872340 (1702 3250);
PAINT GREEN (1702 3250);
DISPLAY INVISIBLE (1702 3250);
FORCEADD TAP..6
R 2
(1700 3300);
FORCEPROP 3 LASTPIN (1650 3300) SIG_NAME M_D_DQ<34>
J 0
(1660 3310);
DISPLAY 0.659574 (1660 3310);
PAINT MONO (1660 3310);
DISPLAY INVISIBLE (1660 3310);
FORCEPROP 1 LASTPIN (1650 3300) BN 34
J 2
(1700 3310);
DISPLAY 0.617021 (1700 3310);
PAINT PINK (1700 3310);
FORCEPROP 2 LAST CDS_LIB mstr_standard
J 2
(1700 3300);
DISPLAY 0.787234 (1700 3300);
PAINT MONO (1700 3300);
DISPLAY INVISIBLE (1700 3300);
FORCEPROP 1 LAST BODY_TYPE PLUMBING
J 2
(1700 3250);
DISPLAY 1.234043 (1700 3250);
PAINT GREEN (1700 3250);
DISPLAY INVISIBLE (1700 3250);
FORCEPROP 1 LAST HDL_TAP TRUE
J 2
(1375 3175);
DISPLAY 1.234043 (1375 3175);
PAINT GREEN (1375 3175);
DISPLAY INVISIBLE (1375 3175);
FORCEPROP 1 LAST PATH I97
J 2
(1702 3300);
DISPLAY 0.872340 (1702 3300);
PAINT GREEN (1702 3300);
DISPLAY INVISIBLE (1702 3300);
FORCEADD TAP..6
R 2
(1700 3100);
FORCEPROP 3 LASTPIN (1650 3100) SIG_NAME M_D_DQ<30>
J 0
(1660 3110);
DISPLAY 0.659574 (1660 3110);
PAINT MONO (1660 3110);
DISPLAY INVISIBLE (1660 3110);
FORCEPROP 1 LASTPIN (1650 3100) BN 30
J 2
(1700 3110);
DISPLAY 0.617021 (1700 3110);
PAINT PINK (1700 3110);
FORCEPROP 2 LAST CDS_LIB mstr_standard
J 2
(1700 3100);
DISPLAY 0.787234 (1700 3100);
PAINT MONO (1700 3100);
DISPLAY INVISIBLE (1700 3100);
FORCEPROP 1 LAST BODY_TYPE PLUMBING
J 2
(1700 3050);
DISPLAY 1.234043 (1700 3050);
PAINT GREEN (1700 3050);
DISPLAY INVISIBLE (1700 3050);
FORCEPROP 1 LAST HDL_TAP TRUE
J 2
(1375 2975);
DISPLAY 1.234043 (1375 2975);
PAINT GREEN (1375 2975);
DISPLAY INVISIBLE (1375 2975);
FORCEPROP 1 LAST PATH I98
J 2
(1702 3100);
DISPLAY 0.872340 (1702 3100);
PAINT GREEN (1702 3100);
DISPLAY INVISIBLE (1702 3100);
FORCEADD TAP..6
R 2
(1700 3150);
FORCEPROP 3 LASTPIN (1650 3150) SIG_NAME M_D_DQ<31>
J 0
(1660 3160);
DISPLAY 0.659574 (1660 3160);
PAINT MONO (1660 3160);
DISPLAY INVISIBLE (1660 3160);
FORCEPROP 1 LASTPIN (1650 3150) BN 31
J 2
(1700 3160);
DISPLAY 0.617021 (1700 3160);
PAINT PINK (1700 3160);
FORCEPROP 2 LAST CDS_LIB mstr_standard
J 2
(1700 3150);
DISPLAY 0.787234 (1700 3150);
PAINT MONO (1700 3150);
DISPLAY INVISIBLE (1700 3150);
FORCEPROP 1 LAST BODY_TYPE PLUMBING
J 2
(1700 3100);
DISPLAY 1.234043 (1700 3100);
PAINT GREEN (1700 3100);
DISPLAY INVISIBLE (1700 3100);
FORCEPROP 1 LAST HDL_TAP TRUE
J 2
(1375 3025);
DISPLAY 1.234043 (1375 3025);
PAINT GREEN (1375 3025);
DISPLAY INVISIBLE (1375 3025);
FORCEPROP 1 LAST PATH I99
J 2
(1702 3150);
DISPLAY 0.872340 (1702 3150);
PAINT GREEN (1702 3150);
DISPLAY INVISIBLE (1702 3150);
FORCEADD INTEL_CORP_BPAGE..1
(6075 175);
FORCEPROP 1 LAST CDS_CON_LAST_MODIFIED Fri Jun 16 17:48:19 2017
J 0
(4650 500);
PAINT ORANGE (4650 500);
DISPLAY INVISIBLE (4650 500);
FORCEPROP 1 LAST CUSTOM_TXT_CDS <CURRENT_DESIGN_SHEET> OF <TOTAL_DESIGN_SHEETS>
J 0
(5575 200);
PAINT ORANGE (5575 200);
FORCEPROP 1 LAST CUSTOM_TXT_CDS <CON_LAST_MODIFIED>
J 0
(2075 275);
PAINT ORANGE (2075 275);
FORCEPROP 2 LAST CUSTOM_TXT_CDS <XR_PAGE_TITLE>
J 0
(-1815 5425);
DISPLAY 0.638298 (-1815 5425);
PAINT PINK (-1815 5425);
DISPLAY INVISIBLE (-1815 5425);
FORCEPROP 1 LAST SCH_TITLE CPU0 DDR4 CH D DIMM1
J 0
(-1875 225);
DISPLAY 1.212766 (-1875 225);
PAINT ORANGE (-1875 225);
FORCEPROP 2 LAST CDS_LIB mstr_symbols
J 0
(6075 175);
PAINT MONO (6075 175);
DISPLAY INVISIBLE (6075 175);
FORCEPROP 2 LAST PAGE_BORDER TRUE
J 0
(-1815 5425);
DISPLAY 0.638298 (-1815 5425);
PAINT PINK (-1815 5425);
DISPLAY INVISIBLE (-1815 5425);
FORCEPROP 1 LAST COMMENT_BODY TRUE
J 0
(6087 187);
DISPLAY 0.468085 (6087 187);
PAINT GREEN (6087 187);
DISPLAY INVISIBLE (6087 187);
FORCEPROP 2 LAST CDS_XR_PAGE_TITLE CR-50 : @BASEBOARD_FAB2_LIB.BASEBOARD_FAB2(SCH_1):PAGE50
J 0
(-1815 5425);
DISPLAY 0.638298 (-1815 5425);
PAINT PINK (-1815 5425);
DISPLAY INVISIBLE (-1815 5425);
FORCEADD BOM_NOTE..1
(-1650 4975);
FORCEPROP 0 LAST L1 UNSTUFF FOR SKU B
J 0
(-1800 4875);
DISPLAY 1.063830 (-1800 4875);
PAINT WHITE (-1800 4875);
FORCEPROP 2 LAST BOM_COST SB
J 0
(-1800 4950);
DISPLAY 1.361702 (-1800 4950);
PAINT ORANGE (-1800 4950);
DISPLAY INVISIBLE (-1800 4950);
FORCEPROP 2 LAST CDS_LIB mstr_symbols
J 0
(-1650 4975);
PAINT ORANGE (-1650 4975);
DISPLAY INVISIBLE (-1650 4975);
FORCEPROP 1 LAST COMMENT_BODY TRUE
J 0
(-1625 5075);
DISPLAY 1.319149 (-1625 5075);
PAINT ORANGE (-1625 5075);
DISPLAY INVISIBLE (-1625 5075);
FORCEPROP 2 LAST ROOM SB_HEADERS
J 0
(-1800 4950);
DISPLAY 1.361702 (-1800 4950);
PAINT ORANGE (-1800 4950);
DISPLAY INVISIBLE (-1800 4950);
WIRE 16 -1 (5950 900)(5950 800);
WIRE 16 -1 (5950 900)(5950 950);
WIRE 16 -1 (5950 900)(5750 900);
WIRE 16 -1 (5950 950)(5950 1000);
WIRE 16 -1 (5750 950)(5950 950);
WIRE 16 -1 (5950 1000)(5950 1050);
WIRE 16 -1 (5950 1000)(5750 1000);
WIRE 16 -1 (5950 1050)(5950 1100);
WIRE 16 -1 (5950 1050)(5750 1050);
WIRE 16 -1 (5950 1100)(5950 1150);
WIRE 16 -1 (5750 1100)(5950 1100);
WIRE 16 -1 (5950 1150)(5950 1200);
WIRE 16 -1 (5950 1150)(5750 1150);
WIRE 16 -1 (5950 1200)(5950 1250);
WIRE 16 -1 (5750 1200)(5950 1200);
WIRE 16 -1 (5950 1250)(5950 1300);
WIRE 16 -1 (5950 1250)(5750 1250);
WIRE 16 -1 (5950 1300)(5950 1350);
WIRE 16 -1 (5950 1300)(5750 1300);
WIRE 16 -1 (5950 1350)(5950 1400);
WIRE 16 -1 (5950 1350)(5750 1350);
WIRE 16 -1 (5950 1400)(5950 1450);
WIRE 16 -1 (5750 1400)(5950 1400);
WIRE 16 -1 (5950 1450)(5950 1500);
WIRE 16 -1 (5750 1450)(5950 1450);
WIRE 16 -1 (5950 1500)(5950 1550);
WIRE 16 -1 (5950 1500)(5750 1500);
WIRE 16 -1 (5950 1550)(5950 1600);
WIRE 16 -1 (5750 1550)(5950 1550);
WIRE 16 -1 (5950 1600)(5950 1650);
WIRE 16 -1 (5950 1600)(5750 1600);
WIRE 16 -1 (5950 1650)(5950 1700);
WIRE 16 -1 (5750 1650)(5950 1650);
WIRE 16 -1 (5950 1700)(5950 1750);
WIRE 16 -1 (5950 1700)(5750 1700);
WIRE 16 -1 (5950 1750)(5950 1800);
WIRE 16 -1 (5750 1750)(5950 1750);
WIRE 16 -1 (5950 1800)(5950 1850);
WIRE 16 -1 (5950 1800)(5750 1800);
WIRE 16 -1 (5950 1850)(5950 1900);
WIRE 16 -1 (5950 1850)(5750 1850);
WIRE 16 -1 (5950 1900)(5950 1950);
WIRE 16 -1 (5750 1900)(5950 1900);
WIRE 16 -1 (5950 1950)(5950 2000);
WIRE 16 -1 (5950 1950)(5750 1950);
WIRE 16 -1 (5950 2000)(5950 2050);
WIRE 16 -1 (5750 2000)(5950 2000);
WIRE 16 -1 (5950 2050)(5950 2100);
WIRE 16 -1 (5950 2050)(5750 2050);
WIRE 16 -1 (5950 2100)(5950 2150);
WIRE 16 -1 (5750 2100)(5950 2100);
WIRE 16 -1 (5950 2150)(5950 2200);
WIRE 16 -1 (5950 2150)(5750 2150);
WIRE 16 -1 (5950 2200)(5950 2250);
WIRE 16 -1 (5750 2200)(5950 2200);
WIRE 16 -1 (5950 2250)(5950 2300);
WIRE 16 -1 (5950 2250)(5750 2250);
WIRE 16 -1 (5950 2300)(5950 2350);
WIRE 16 -1 (5750 2300)(5950 2300);
WIRE 16 -1 (5950 2350)(5950 2400);
WIRE 16 -1 (5950 2350)(5750 2350);
WIRE 16 -1 (5950 2400)(5950 2450);
WIRE 16 -1 (5750 2400)(5950 2400);
WIRE 16 -1 (5950 2450)(5950 2500);
WIRE 16 -1 (5950 2450)(5750 2450);
WIRE 16 -1 (5950 2500)(5950 2550);
WIRE 16 -1 (5750 2500)(5950 2500);
WIRE 16 -1 (5950 2550)(5950 2600);
WIRE 16 -1 (5950 2550)(5750 2550);
WIRE 16 -1 (5950 2600)(5950 2650);
WIRE 16 -1 (5750 2600)(5950 2600);
WIRE 16 -1 (5950 2650)(5950 2700);
WIRE 16 -1 (5950 2650)(5750 2650);
WIRE 16 -1 (5950 2700)(5950 2750);
WIRE 16 -1 (5750 2700)(5950 2700);
WIRE 16 -1 (5950 2750)(5950 2800);
WIRE 16 -1 (5950 2750)(5750 2750);
WIRE 16 -1 (5950 2800)(5950 2850);
WIRE 16 -1 (5750 2800)(5950 2800);
WIRE 16 -1 (5950 2850)(5950 2900);
WIRE 16 -1 (5950 2850)(5750 2850);
WIRE 16 -1 (5950 2900)(5950 2950);
WIRE 16 -1 (5750 2900)(5950 2900);
WIRE 16 -1 (5950 2950)(5950 3000);
WIRE 16 -1 (5950 2950)(5750 2950);
WIRE 16 -1 (5950 3000)(5950 3050);
WIRE 16 -1 (5750 3000)(5950 3000);
WIRE 16 -1 (5950 3050)(5950 3100);
WIRE 16 -1 (5950 3050)(5750 3050);
WIRE 16 -1 (5950 3100)(5950 3150);
WIRE 16 -1 (5750 3100)(5950 3100);
WIRE 16 -1 (5950 3150)(5950 3200);
WIRE 16 -1 (5950 3150)(5750 3150);
WIRE 16 -1 (5950 3200)(5750 3200);
WIRE 16 -1 (-1650 2050)(-1650 1950);
WIRE 16 -1 (-1650 1950)(150 1950);
WIRE 16 -1 (150 1800)(150 1950);
WIRE 16 -1 (150 1950)(450 1950);
WIRE 16 -1 (150 1800)(450 1800);
WIRE 16 -1 (-1200 1300)(-1200 1200);
WIRE 16 -1 (-1350 1900)(-1350 1825);
WIRE 16 -1 (250 1900)(-1350 1900);
WIRE 16 -1 (250 1850)(250 1900);
WIRE 16 -1 (250 1900)(450 1900);
WIRE 16 -1 (250 1850)(450 1850);
WIRE 16 -1 (4100 2400)(4100 2575);
WIRE 16 -1 (4100 2350)(4100 2400);
WIRE 16 -1 (3900 2400)(4100 2400);
WIRE 16 -1 (3900 2350)(4100 2350);
WIRE 16 -1 (4550 900)(4550 800);
WIRE 16 -1 (4550 900)(4550 950);
WIRE 16 -1 (4550 900)(4750 900);
WIRE 16 -1 (4550 950)(4550 1000);
WIRE 16 -1 (4750 950)(4550 950);
WIRE 16 -1 (4550 1000)(4550 1050);
WIRE 16 -1 (4550 1000)(4750 1000);
WIRE 16 -1 (4550 1050)(4550 1100);
WIRE 16 -1 (4550 1050)(4750 1050);
WIRE 16 -1 (4550 1100)(4550 1150);
WIRE 16 -1 (4750 1100)(4550 1100);
WIRE 16 -1 (4550 1150)(4550 1200);
WIRE 16 -1 (4550 1150)(4750 1150);
WIRE 16 -1 (4550 1200)(4550 1250);
WIRE 16 -1 (4750 1200)(4550 1200);
WIRE 16 -1 (4550 1250)(4550 1300);
WIRE 16 -1 (4550 1250)(4750 1250);
WIRE 16 -1 (4550 1300)(4550 1350);
WIRE 16 -1 (4550 1300)(4750 1300);
WIRE 16 -1 (4550 1350)(4550 1400);
WIRE 16 -1 (4550 1350)(4750 1350);
WIRE 16 -1 (4550 1400)(4550 1450);
WIRE 16 -1 (4750 1400)(4550 1400);
WIRE 16 -1 (4550 1450)(4550 1500);
WIRE 16 -1 (4750 1450)(4550 1450);
WIRE 16 -1 (4550 1500)(4550 1550);
WIRE 16 -1 (4550 1500)(4750 1500);
WIRE 16 -1 (4550 1550)(4550 1600);
WIRE 16 -1 (4750 1550)(4550 1550);
WIRE 16 -1 (4550 1600)(4550 1650);
WIRE 16 -1 (4550 1600)(4750 1600);
WIRE 16 -1 (4550 1650)(4550 1700);
WIRE 16 -1 (4750 1650)(4550 1650);
WIRE 16 -1 (4550 1700)(4550 1750);
WIRE 16 -1 (4550 1700)(4750 1700);
WIRE 16 -1 (4550 1750)(4550 1800);
WIRE 16 -1 (4750 1750)(4550 1750);
WIRE 16 -1 (4550 1800)(4550 1850);
WIRE 16 -1 (4550 1800)(4750 1800);
WIRE 16 -1 (4550 1850)(4550 1900);
WIRE 16 -1 (4550 1850)(4750 1850);
WIRE 16 -1 (4550 1900)(4550 1950);
WIRE 16 -1 (4750 1900)(4550 1900);
WIRE 16 -1 (4550 1950)(4550 2000);
WIRE 16 -1 (4550 1950)(4750 1950);
WIRE 16 -1 (4550 2000)(4550 2050);
WIRE 16 -1 (4750 2000)(4550 2000);
WIRE 16 -1 (4550 2050)(4550 2100);
WIRE 16 -1 (4550 2050)(4750 2050);
WIRE 16 -1 (4550 2100)(4550 2150);
WIRE 16 -1 (4750 2100)(4550 2100);
WIRE 16 -1 (4550 2150)(4550 2200);
WIRE 16 -1 (4550 2150)(4750 2150);
WIRE 16 -1 (4550 2200)(4550 2250);
WIRE 16 -1 (4750 2200)(4550 2200);
WIRE 16 -1 (4550 2250)(4550 2300);
WIRE 16 -1 (4550 2250)(4750 2250);
WIRE 16 -1 (4550 2300)(4550 2350);
WIRE 16 -1 (4750 2300)(4550 2300);
WIRE 16 -1 (4550 2350)(4550 2400);
WIRE 16 -1 (4550 2350)(4750 2350);
WIRE 16 -1 (4550 2400)(4550 2450);
WIRE 16 -1 (4750 2400)(4550 2400);
WIRE 16 -1 (4550 2450)(4550 2500);
WIRE 16 -1 (4550 2450)(4750 2450);
WIRE 16 -1 (4550 2500)(4550 2550);
WIRE 16 -1 (4750 2500)(4550 2500);
WIRE 16 -1 (4550 2550)(4550 2600);
WIRE 16 -1 (4550 2550)(4750 2550);
WIRE 16 -1 (4550 2600)(4550 2650);
WIRE 16 -1 (4750 2600)(4550 2600);
WIRE 16 -1 (4550 2650)(4550 2700);
WIRE 16 -1 (4550 2650)(4750 2650);
WIRE 16 -1 (4550 2700)(4550 2750);
WIRE 16 -1 (4750 2700)(4550 2700);
WIRE 16 -1 (4550 2750)(4550 2800);
WIRE 16 -1 (4550 2750)(4750 2750);
WIRE 16 -1 (4550 2800)(4550 2850);
WIRE 16 -1 (4750 2800)(4550 2800);
WIRE 16 -1 (4550 2850)(4550 2900);
WIRE 16 -1 (4550 2850)(4750 2850);
WIRE 16 -1 (4550 2900)(4550 2950);
WIRE 16 -1 (4750 2900)(4550 2900);
WIRE 16 -1 (4550 2950)(4550 3000);
WIRE 16 -1 (4550 2950)(4750 2950);
WIRE 16 -1 (4550 3000)(4550 3050);
WIRE 16 -1 (4750 3000)(4550 3000);
WIRE 16 -1 (4550 3050)(4550 3100);
WIRE 16 -1 (4550 3050)(4750 3050);
WIRE 16 -1 (4550 3100)(4550 3150);
WIRE 16 -1 (4750 3100)(4550 3100);
WIRE 16 -1 (4550 3150)(4550 3200);
WIRE 16 -1 (4550 3150)(4750 3150);
WIRE 16 -1 (4550 3200)(4750 3200);
WIRE 16 -1 (2700 2500)(2700 2400);
WIRE 16 -1 (2700 2400)(2700 2350);
WIRE 16 -1 (2700 2400)(2900 2400);
WIRE 16 -1 (2700 2350)(2700 2300);
WIRE 16 -1 (2700 2350)(2900 2350);
WIRE 16 -1 (2700 2300)(2700 2250);
WIRE 16 -1 (2900 2300)(2700 2300);
WIRE 16 -1 (2700 2250)(2700 2200);
WIRE 16 -1 (2700 2250)(2900 2250);
WIRE 16 -1 (2700 2200)(2900 2200);
WIRE 16 -1 (2550 2200)(2550 2100);
WIRE 16 -1 (2550 2100)(2700 2100);
WIRE 16 -1 (2700 2050)(2700 2100);
WIRE 16 -1 (2700 2100)(2900 2100);
WIRE 16 -1 (2700 2050)(2900 2050);
WIRE 16 -1 (2300 2050)(2300 1950);
WIRE 16 -1 (2300 1950)(2700 1950);
WIRE 16 -1 (2700 1900)(2700 1950);
WIRE 16 -1 (2700 1950)(2900 1950);
WIRE 16 -1 (2700 1850)(2700 1900);
WIRE 16 -1 (2700 1900)(2900 1900);
WIRE 16 -1 (2700 1800)(2700 1850);
WIRE 16 -1 (2700 1850)(2900 1850);
WIRE 16 -1 (2700 1750)(2700 1800);
WIRE 16 -1 (2700 1800)(2900 1800);
WIRE 16 -1 (2700 1700)(2700 1750);
WIRE 16 -1 (2700 1750)(2900 1750);
WIRE 16 -1 (2700 1650)(2700 1700);
WIRE 16 -1 (2700 1700)(2900 1700);
WIRE 16 -1 (2700 1600)(2700 1650);
WIRE 16 -1 (2700 1650)(2900 1650);
WIRE 16 -1 (2700 1550)(2700 1600);
WIRE 16 -1 (2700 1600)(2900 1600);
WIRE 16 -1 (2700 1500)(2700 1550);
WIRE 16 -1 (2700 1550)(2900 1550);
WIRE 16 -1 (2700 1450)(2700 1500);
WIRE 16 -1 (2700 1500)(2900 1500);
WIRE 16 -1 (2700 1400)(2700 1450);
WIRE 16 -1 (2700 1450)(2900 1450);
WIRE 16 -1 (2700 1350)(2700 1400);
WIRE 16 -1 (2700 1400)(2900 1400);
WIRE 16 -1 (2700 1300)(2700 1350);
WIRE 16 -1 (2700 1350)(2900 1350);
WIRE 16 -1 (2700 1250)(2700 1300);
WIRE 16 -1 (2700 1300)(2900 1300);
WIRE 16 -1 (2700 1200)(2700 1250);
WIRE 16 -1 (2700 1250)(2900 1250);
WIRE 16 -1 (2700 1150)(2700 1200);
WIRE 16 -1 (2700 1200)(2900 1200);
WIRE 16 -1 (2700 1100)(2700 1150);
WIRE 16 -1 (2700 1150)(2900 1150);
WIRE 16 -1 (2700 1050)(2700 1100);
WIRE 16 -1 (2700 1100)(2900 1100);
WIRE 16 -1 (2700 1000)(2700 1050);
WIRE 16 -1 (2700 1050)(2900 1050);
WIRE 16 -1 (2700 950)(2700 1000);
WIRE 16 -1 (2700 1000)(2900 1000);
WIRE 16 -1 (2700 900)(2700 950);
WIRE 16 -1 (2700 950)(2900 950);
WIRE 16 -1 (2700 850)(2700 900);
WIRE 16 -1 (2700 900)(2900 900);
WIRE 16 -1 (2700 800)(2700 850);
WIRE 16 -1 (2700 850)(2900 850);
WIRE 16 -1 (2700 750)(2700 800);
WIRE 16 -1 (2700 800)(2900 800);
WIRE 16 -1 (2700 700)(2700 750);
WIRE 16 -1 (2700 750)(2900 750);
WIRE 16 -1 (2700 700)(2900 700);
WIRE 17 -1 (2200 4800)(1750 4800);
FORCEPROP 2 LAST SIG_NAME M_D_DQ<63:0>
J 0
(1790 4810);
DISPLAY 0.617021 (1790 4810);
PAINT ORANGE (1790 4810);
WIRE 17 -1 (1750 4775)(1750 4800);
WIRE 17 -1 (1750 4725)(1750 4775);
WIRE 17 -1 (1750 4675)(1750 4725);
WIRE 17 -1 (1750 4625)(1750 4675);
WIRE 17 -1 (1750 4575)(1750 4625);
WIRE 17 -1 (1750 4525)(1750 4575);
WIRE 17 -1 (1750 4475)(1750 4525);
WIRE 17 -1 (1750 4425)(1750 4475);
WIRE 17 -1 (1750 4375)(1750 4425);
WIRE 17 -1 (1750 4325)(1750 4375);
WIRE 17 -1 (1750 4275)(1750 4325);
WIRE 17 -1 (1750 4225)(1750 4275);
WIRE 17 -1 (1750 4175)(1750 4225);
WIRE 17 -1 (1750 4125)(1750 4175);
WIRE 17 -1 (1750 4075)(1750 4125);
WIRE 17 -1 (1750 4025)(1750 4075);
WIRE 17 -1 (1750 3975)(1750 4025);
WIRE 17 -1 (1750 3925)(1750 3975);
WIRE 17 -1 (1750 3875)(1750 3925);
WIRE 17 -1 (1750 3825)(1750 3875);
WIRE 17 -1 (1750 3775)(1750 3825);
WIRE 17 -1 (1750 3725)(1750 3775);
WIRE 17 -1 (1750 3675)(1750 3725);
WIRE 17 -1 (1750 3625)(1750 3675);
WIRE 17 -1 (1750 3575)(1750 3625);
WIRE 17 -1 (1750 3525)(1750 3575);
WIRE 17 -1 (1750 3475)(1750 3525);
WIRE 17 -1 (1750 3425)(1750 3475);
WIRE 17 -1 (1750 3375)(1750 3425);
WIRE 17 -1 (1750 3325)(1750 3375);
WIRE 17 -1 (1750 3275)(1750 3325);
WIRE 17 -1 (1750 3225)(1750 3275);
WIRE 17 -1 (1750 3175)(1750 3225);
WIRE 17 -1 (1750 3125)(1750 3175);
WIRE 17 -1 (1750 3075)(1750 3125);
WIRE 17 -1 (1750 3025)(1750 3075);
WIRE 17 -1 (1750 2975)(1750 3025);
WIRE 17 -1 (1750 2925)(1750 2975);
WIRE 17 -1 (1750 2875)(1750 2925);
WIRE 17 -1 (1750 2825)(1750 2875);
WIRE 17 -1 (1750 2775)(1750 2825);
WIRE 17 -1 (1750 2725)(1750 2775);
WIRE 17 -1 (1750 2675)(1750 2725);
WIRE 17 -1 (1750 2625)(1750 2675);
WIRE 17 -1 (1750 2575)(1750 2625);
WIRE 17 -1 (1750 2525)(1750 2575);
WIRE 17 -1 (1750 2475)(1750 2525);
WIRE 17 -1 (1750 1625)(1750 1675);
WIRE 17 -1 (1750 2425)(1750 2475);
WIRE 17 -1 (1750 2375)(1750 2425);
WIRE 17 -1 (1750 1675)(1750 1725);
WIRE 17 -1 (1750 1725)(1750 1775);
WIRE 17 -1 (1750 2325)(1750 2375);
WIRE 17 -1 (1750 2275)(1750 2325);
WIRE 17 -1 (1750 1775)(1750 1825);
WIRE 17 -1 (1750 1825)(1750 1875);
WIRE 17 -1 (1750 2225)(1750 2275);
WIRE 17 -1 (1750 2175)(1750 2225);
WIRE 17 -1 (1750 1875)(1750 1925);
WIRE 17 -1 (1750 1925)(1750 1975);
WIRE 17 -1 (1750 2125)(1750 2175);
WIRE 17 -1 (1750 2075)(1750 2125);
WIRE 17 -1 (1750 1975)(1750 2025);
WIRE 17 -1 (1750 2025)(1750 2075);
WIRE 17 -1 (150 2375)(150 2425);
WIRE 17 -1 (150 2750)(-500 2750);
FORCEPROP 2 LAST SIG_NAME M_D_ECC<7:0>
J 0
(-475 2760);
DISPLAY 0.617021 (-475 2760);
PAINT ORANGE (-475 2760);
WIRE 17 -1 (150 2725)(150 2750);
WIRE 17 -1 (150 2425)(150 2475);
WIRE 17 -1 (150 2475)(150 2525);
WIRE 17 -1 (150 2675)(150 2725);
WIRE 17 -1 (150 2625)(150 2675);
WIRE 17 -1 (150 2525)(150 2575);
WIRE 17 -1 (150 2575)(150 2625);
WIRE 17 -1 (150 3050)(-500 3050);
FORCEPROP 2 LAST SIG_NAME M_D_CKE<3:0>
J 0
(-475 3060);
DISPLAY 0.617021 (-475 3060);
PAINT ORANGE (-475 3060);
WIRE 17 -1 (150 2975)(150 3025);
WIRE 17 -1 (150 3025)(150 3050);
WIRE 17 -1 (150 2900)(-500 2900);
FORCEPROP 2 LAST SIG_NAME M_D_ODT<3:0>
J 0
(-475 2910);
DISPLAY 0.617021 (-475 2910);
PAINT ORANGE (-475 2910);
WIRE 17 -1 (150 2875)(150 2900);
WIRE 17 -1 (150 2825)(150 2875);
WIRE 17 -1 (-50 3550)(-500 3550);
FORCEPROP 2 LAST SIG_NAME M_D_CLK_DN<3:0>
J 0
(-450 3560);
DISPLAY 0.617021 (-450 3560);
PAINT ORANGE (-450 3560);
WIRE 17 -1 (-50 3550)(-50 3525);
WIRE 17 -1 (-50 3525)(-50 3425);
WIRE 17 -1 (150 3600)(-500 3600);
FORCEPROP 2 LAST SIG_NAME M_D_CLK_DP<3:0>
J 0
(-450 3610);
DISPLAY 0.617021 (-450 3610);
PAINT ORANGE (-450 3610);
WIRE 17 -1 (150 3600)(150 3575);
WIRE 17 -1 (150 3475)(150 3575);
WIRE 17 -1 (150 3125)(150 3175);
WIRE 17 -1 (150 3300)(-500 3300);
FORCEPROP 2 LAST SIG_NAME M_D_CS_N<7:0>
J 0
(-476 3316);
DISPLAY 0.617021 (-476 3316);
PAINT ORANGE (-476 3316);
WIRE 17 -1 (150 3300)(150 3275);
WIRE 17 -1 (150 3175)(150 3225);
WIRE 17 -1 (150 3225)(150 3275);
WIRE 17 -1 (150 3850)(-500 3850);
FORCEPROP 2 LAST SIG_NAME M_D_BA<1:0>
J 0
(-475 3860);
DISPLAY 0.617021 (-475 3860);
PAINT ORANGE (-475 3860);
WIRE 17 -1 (150 3850)(150 3825);
WIRE 17 -1 (150 3775)(150 3825);
WIRE 17 -1 (-500 4800)(150 4800);
FORCEPROP 2 LAST SIG_NAME M_D_MA<17:0>
J 0
(-475 4810);
DISPLAY 0.617021 (-475 4810);
PAINT ORANGE (-475 4810);
WIRE 17 -1 (150 4775)(150 4800);
WIRE 17 -1 (150 4725)(150 4775);
WIRE 17 -1 (150 4675)(150 4725);
WIRE 17 -1 (150 4625)(150 4675);
WIRE 17 -1 (150 4575)(150 4625);
WIRE 17 -1 (150 4525)(150 4575);
WIRE 17 -1 (150 4475)(150 4525);
WIRE 17 -1 (150 4425)(150 4475);
WIRE 17 -1 (150 4375)(150 4425);
WIRE 17 -1 (150 4325)(150 4375);
WIRE 17 -1 (150 4275)(150 4325);
WIRE 17 -1 (150 4225)(150 4275);
WIRE 17 -1 (150 4175)(150 4225);
WIRE 17 -1 (150 4125)(150 4175);
WIRE 17 -1 (150 4075)(150 4125);
WIRE 17 -1 (150 4025)(150 4075);
WIRE 17 -1 (150 3975)(150 4025);
WIRE 17 -1 (150 3925)(150 3975);
WIRE 17 -1 (-500 3750)(150 3750);
FORCEPROP 2 LAST SIG_NAME M_D_BG<1:0>
J 0
(-475 3760);
DISPLAY 0.617021 (-475 3760);
PAINT ORANGE (-475 3760);
WIRE 17 -1 (150 3750)(150 3725);
WIRE 17 -1 (150 3675)(150 3725);
WIRE 17 -1 (5050 4850)(4150 4850);
FORCEPROP 2 LAST SIG_NAME M_D_DQS_DP<17:0>
J 0
(4450 4860);
DISPLAY 0.617021 (4450 4860);
PAINT ORANGE (4450 4860);
WIRE 17 -1 (4150 4825)(4150 4850);
WIRE 17 -1 (4150 4725)(4150 4825);
WIRE 17 -1 (4150 4625)(4150 4725);
WIRE 17 -1 (4150 4525)(4150 4625);
WIRE 17 -1 (4150 4425)(4150 4525);
WIRE 17 -1 (4150 4325)(4150 4425);
WIRE 17 -1 (4150 4225)(4150 4325);
WIRE 17 -1 (4150 4125)(4150 4225);
WIRE 17 -1 (4150 4025)(4150 4125);
WIRE 17 -1 (4150 3925)(4150 4025);
WIRE 17 -1 (4150 3825)(4150 3925);
WIRE 17 -1 (4150 3725)(4150 3825);
WIRE 17 -1 (4150 3625)(4150 3725);
WIRE 17 -1 (4150 3525)(4150 3625);
WIRE 17 -1 (4150 3425)(4150 3525);
WIRE 17 -1 (4150 3325)(4150 3425);
WIRE 17 -1 (4150 3225)(4150 3325);
WIRE 17 -1 (4150 3125)(4150 3225);
WIRE 17 -1 (5050 4800)(4400 4800);
FORCEPROP 2 LAST SIG_NAME M_D_DQS_DN<17:0>
J 0
(4450 4810);
DISPLAY 0.617021 (4450 4810);
PAINT ORANGE (4450 4810);
WIRE 17 -1 (4400 4775)(4400 4800);
WIRE 17 -1 (4400 4675)(4400 4775);
WIRE 17 -1 (4400 4575)(4400 4675);
WIRE 17 -1 (4400 4475)(4400 4575);
WIRE 17 -1 (4400 4375)(4400 4475);
WIRE 17 -1 (4400 4275)(4400 4375);
WIRE 17 -1 (4400 4175)(4400 4275);
WIRE 17 -1 (4400 4075)(4400 4175);
WIRE 17 -1 (4400 3975)(4400 4075);
WIRE 17 -1 (4400 3875)(4400 3975);
WIRE 17 -1 (4400 3775)(4400 3875);
WIRE 17 -1 (4400 3675)(4400 3775);
WIRE 17 -1 (4400 3575)(4400 3675);
WIRE 17 -1 (4400 3475)(4400 3575);
WIRE 17 -1 (4400 3375)(4400 3475);
WIRE 17 -1 (4400 3275)(4400 3375);
WIRE 17 -1 (4400 3175)(4400 3275);
WIRE 17 -1 (4400 3075)(4400 3175);
WIRE 16 -1 (1650 2450)(1450 2450);
WIRE 16 -1 (1650 2500)(1450 2500);
WIRE 16 -1 (3850 3100)(4050 3100);
WIRE 16 -1 (4300 3550)(3850 3550);
WIRE 16 -1 (4050 3500)(3850 3500);
WIRE 16 -1 (1650 4500)(1450 4500);
WIRE 16 -1 (1650 4550)(1450 4550);
WIRE 16 -1 (4300 4450)(3850 4450);
WIRE 16 -1 (4300 4350)(3850 4350);
WIRE 16 -1 (1650 4250)(1450 4250);
WIRE 16 -1 (1650 4050)(1450 4050);
WIRE 16 -1 (-400 1450)(450 1450);
FORCEPROP 2 LAST SIG_NAME TP_CH_D_DIMM_D1_RFU_1
J 0
(-350 1460);
DISPLAY 0.617021 (-350 1460);
PAINT ORANGE (-350 1460);
FORCEPROP 2 LASTPROP $XRERR UNIQUE?
J 0
(-640 1450);
DISPLAY 0.638298 (-640 1450);
PAINT MONO (-640 1450);
DISPLAY INVISIBLE (-640 1450);
WIRE 16 -1 (1650 1600)(1450 1600);
WIRE 16 -1 (450 4600)(250 4600);
WIRE 16 -1 (-400 1300)(450 1300);
FORCEPROP 2 LAST SIG_NAME FM_ADR_COMPLETE_DEF_N
J 0
(-350 1310);
DISPLAY 0.617021 (-350 1310);
PAINT ORANGE (-350 1310);
WIRE 16 -1 (-1200 1500)(-1200 1600);
WIRE 16 -1 (450 1600)(-1200 1600);
FORCEPROP 2 LAST SIG_NAME M_D_VREF
J 0
(-300 1610);
DISPLAY 0.617021 (-300 1610);
PAINT ORANGE (-300 1610);
WIRE 16 -1 (-1300 1600)(-1200 1600);
WIRE 16 -1 (1650 3550)(1450 3550);
WIRE 16 -1 (4300 3850)(3850 3850);
WIRE 16 -1 (3850 3150)(4300 3150);
WIRE 16 -1 (4300 3250)(3850 3250);
WIRE 16 -1 (4050 3300)(3850 3300);
WIRE 16 -1 (1650 4450)(1450 4450);
WIRE 16 -1 (1650 4200)(1450 4200);
WIRE 16 -1 (4300 4150)(3850 4150);
WIRE 16 -1 (4300 3950)(3850 3950);
WIRE 16 -1 (4300 3750)(3850 3750);
WIRE 16 -1 (4300 3650)(3850 3650);
WIRE 16 -1 (4300 3450)(3850 3450);
WIRE 16 -1 (4300 3350)(3850 3350);
WIRE 16 -1 (4300 4750)(3850 4750);
WIRE 16 -1 (4300 4650)(3850 4650);
WIRE 16 -1 (4300 4550)(3850 4550);
WIRE 16 -1 (4300 4250)(3850 4250);
WIRE 16 -1 (4300 4050)(3850 4050);
WIRE 16 -1 (3850 3050)(4300 3050);
WIRE 16 -1 (4050 4800)(3850 4800);
WIRE 16 -1 (4050 4700)(3850 4700);
WIRE 16 -1 (4050 4600)(3850 4600);
WIRE 16 -1 (4050 4500)(3850 4500);
WIRE 16 -1 (4050 4400)(3850 4400);
WIRE 16 -1 (4050 4300)(3850 4300);
WIRE 16 -1 (4050 4200)(3850 4200);
WIRE 16 -1 (4050 4100)(3850 4100);
WIRE 16 -1 (1650 4100)(1450 4100);
WIRE 16 -1 (1650 4150)(1450 4150);
WIRE 16 -1 (1650 4300)(1450 4300);
WIRE 16 -1 (1650 4350)(1450 4350);
WIRE 16 -1 (1650 4400)(1450 4400);
WIRE 16 -1 (1650 4600)(1450 4600);
WIRE 16 -1 (1650 4650)(1450 4650);
WIRE 16 -1 (1650 4700)(1450 4700);
WIRE 16 -1 (1650 4750)(1450 4750);
WIRE 16 -1 (450 4700)(250 4700);
WIRE 16 -1 (450 4650)(250 4650);
WIRE 16 -1 (450 4750)(250 4750);
WIRE 16 -1 (450 4450)(250 4450);
WIRE 16 -1 (450 4400)(250 4400);
WIRE 16 -1 (450 4350)(250 4350);
WIRE 16 -1 (450 4300)(250 4300);
WIRE 16 -1 (450 4250)(250 4250);
WIRE 16 -1 (450 4200)(250 4200);
WIRE 16 -1 (450 4150)(250 4150);
WIRE 16 -1 (450 4100)(250 4100);
WIRE 16 -1 (450 4550)(250 4550);
WIRE 16 -1 (450 4500)(250 4500);
WIRE 16 -1 (4050 4000)(3850 4000);
WIRE 16 -1 (4050 3900)(3850 3900);
WIRE 16 -1 (4050 3800)(3850 3800);
WIRE 16 -1 (4050 3700)(3850 3700);
WIRE 16 -1 (4050 3600)(3850 3600);
WIRE 16 -1 (4050 3400)(3850 3400);
WIRE 16 -1 (3850 3200)(4050 3200);
WIRE 16 -1 (1650 3950)(1450 3950);
WIRE 16 -1 (1650 4000)(1450 4000);
WIRE 16 -1 (1650 3500)(1450 3500);
WIRE 16 -1 (1650 3400)(1450 3400);
WIRE 16 -1 (1650 3350)(1450 3350);
WIRE 16 -1 (1650 3100)(1450 3100);
WIRE 16 -1 (1650 3150)(1450 3150);
WIRE 16 -1 (1650 3200)(1450 3200);
WIRE 16 -1 (1650 3250)(1450 3250);
WIRE 16 -1 (1650 3300)(1450 3300);
WIRE 16 -1 (1650 3450)(1450 3450);
WIRE 16 -1 (1650 3600)(1450 3600);
WIRE 16 -1 (1650 3650)(1450 3650);
WIRE 16 -1 (1650 3700)(1450 3700);
WIRE 16 -1 (1650 3750)(1450 3750);
WIRE 16 -1 (1650 3800)(1450 3800);
WIRE 16 -1 (1650 3850)(1450 3850);
WIRE 16 -1 (1650 3900)(1450 3900);
WIRE 16 -1 (1650 2350)(1450 2350);
WIRE 16 -1 (1650 2900)(1450 2900);
WIRE 16 -1 (1650 2950)(1450 2950);
WIRE 16 -1 (1650 2050)(1450 2050);
WIRE 16 -1 (1650 2100)(1450 2100);
WIRE 16 -1 (1650 2150)(1450 2150);
WIRE 16 -1 (1650 2200)(1450 2200);
WIRE 16 -1 (1650 2250)(1450 2250);
WIRE 16 -1 (1650 2300)(1450 2300);
WIRE 16 -1 (1650 2400)(1450 2400);
WIRE 16 -1 (1650 2550)(1450 2550);
WIRE 16 -1 (1650 2600)(1450 2600);
WIRE 16 -1 (1650 2650)(1450 2650);
WIRE 16 -1 (1650 2700)(1450 2700);
WIRE 16 -1 (1650 2750)(1450 2750);
WIRE 16 -1 (1650 2800)(1450 2800);
WIRE 16 -1 (1650 2850)(1450 2850);
WIRE 16 -1 (1650 3000)(1450 3000);
WIRE 16 -1 (1650 3050)(1450 3050);
WIRE 16 -1 (450 4000)(250 4000);
WIRE 16 -1 (450 3750)(250 3750);
WIRE 16 -1 (450 3700)(250 3700);
WIRE 16 -1 (450 3650)(250 3650);
WIRE 16 -1 (450 4050)(250 4050);
WIRE 16 -1 (450 3950)(250 3950);
WIRE 16 -1 (450 3900)(250 3900);
WIRE 16 -1 (450 3800)(250 3800);
WIRE 16 -1 (300 3300)(450 3300);
WIRE 16 -1 (300 3350)(-500 3350);
FORCEPROP 2 LAST SIG_NAME M_D_C<2>
J 0
(-475 3360);
DISPLAY 0.617021 (-475 3360);
PAINT ORANGE (-475 3360);
WIRE 16 -1 (300 3350)(300 3300);
WIRE 16 -1 (450 3100)(250 3100);
WIRE 16 -1 (450 3550)(250 3550);
WIRE 16 -1 (450 3400)(50 3400);
WIRE 16 -1 (450 3150)(250 3150);
WIRE 16 -1 (450 3200)(250 3200);
WIRE 16 -1 (450 3250)(250 3250);
WIRE 16 -1 (450 3450)(250 3450);
WIRE 16 -1 (450 3500)(50 3500);
WIRE 16 -1 (450 2950)(250 2950);
WIRE 16 -1 (450 2850)(250 2850);
WIRE 16 -1 (450 2800)(250 2800);
WIRE 16 -1 (450 2700)(250 2700);
WIRE 16 -1 (450 3000)(250 3000);
WIRE 16 -1 (450 2600)(250 2600);
WIRE 16 -1 (450 2650)(250 2650);
WIRE 16 -1 (50 2650)(-500 2650);
FORCEPROP 2 LAST SIG_NAME M_DEF_RST_N
J 0
(-475 2660);
DISPLAY 0.617021 (-475 2660);
PAINT ORANGE (-475 2660);
WIRE 16 -1 (450 2200)(50 2200);
WIRE 16 -1 (50 2200)(50 2650);
WIRE 16 -1 (100 2700)(-500 2700);
FORCEPROP 2 LAST SIG_NAME M_D_PAR
J 0
(-475 2710);
DISPLAY 0.617021 (-475 2710);
PAINT ORANGE (-475 2710);
WIRE 16 -1 (450 2250)(100 2250);
WIRE 16 -1 (100 2250)(100 2700);
WIRE 16 -1 (450 2350)(250 2350);
WIRE 16 -1 (450 2400)(250 2400);
WIRE 16 -1 (450 2450)(250 2450);
WIRE 16 -1 (450 2500)(250 2500);
WIRE 16 -1 (450 2550)(250 2550);
WIRE 16 -1 (1650 1850)(1450 1850);
WIRE 16 -1 (1650 1800)(1450 1800);
WIRE 16 -1 (1650 1750)(1450 1750);
WIRE 16 -1 (1650 1700)(1450 1700);
WIRE 16 -1 (1650 1650)(1450 1650);
WIRE 16 -1 (1650 1900)(1450 1900);
WIRE 16 -1 (1650 1950)(1450 1950);
WIRE 16 -1 (1650 2000)(1450 2000);
WIRE 16 -1 (-350 1700)(450 1700);
FORCEPROP 2 LAST SIG_NAME SMB_DDR_DEF_VPP_SCL
J 0
(-310 1710);
DISPLAY 0.617021 (-310 1710);
PAINT ORANGE (-310 1710);
WIRE 16 -1 (450 1750)(-350 1750);
WIRE 16 -1 (450 2050)(-500 2050);
FORCEPROP 2 LAST SIG_NAME M_D_ACT_N
J 0
(-450 2060);
DISPLAY 0.617021 (-450 2060);
PAINT ORANGE (-450 2060);
WIRE 16 -1 (450 2100)(-525 2100);
FORCEPROP 2 LAST SIG_NAME M_D_ALERT_N
J 0
(-475 2110);
DISPLAY 0.617021 (-475 2110);
PAINT ORANGE (-475 2110);
WIRE 16 -1 (-400 1400)(450 1400);
FORCEPROP 2 LAST SIG_NAME TP_CH_D_DIMM_D1_RFU_0
J 0
(-350 1410);
DISPLAY 0.617021 (-350 1410);
PAINT ORANGE (-350 1410);
FORCEPROP 2 LASTPROP $XRERR UNIQUE?
J 0
(-640 1400);
DISPLAY 0.638298 (-640 1400);
PAINT MONO (-640 1400);
DISPLAY INVISIBLE (-640 1400);
WIRE 16 -1 (-400 1500)(450 1500);
FORCEPROP 2 LAST SIG_NAME TP_CH_D_DIMM_D1_RFU_2
J 0
(-350 1510);
DISPLAY 0.617021 (-350 1510);
PAINT ORANGE (-350 1510);
FORCEPROP 2 LASTPROP $XRERR UNIQUE?
J 0
(-640 1500);
DISPLAY 0.638298 (-640 1500);
PAINT MONO (-640 1500);
DISPLAY INVISIBLE (-640 1500);
WIRE 16 -1 (0 2150)(450 2150);
WIRE 16 -1 (0 2150)(0 2450);
WIRE 16 -1 (0 2450)(-725 2450);
FORCEPROP 2 LAST SIG_NAME FM_DIMM_EVENT_COD_N
J 0
(-752 2465);
DISPLAY 0.617021 (-752 2465);
PAINT ORANGE (-752 2465);
DOT 1 (4550 2750);
DOT 1 (4550 2700);
DOT 1 (250 1900);
DOT 1 (150 1950);
DOT 1 (5950 3150);
DOT 1 (5950 3100);
DOT 1 (5950 3050);
DOT 1 (5950 2950);
DOT 1 (5950 3000);
DOT 1 (5950 2900);
DOT 1 (5950 2850);
DOT 1 (5950 2800);
DOT 1 (5950 2750);
DOT 1 (5950 2700);
DOT 1 (5950 2650);
DOT 1 (5950 2600);
DOT 1 (5950 2550);
DOT 1 (5950 2450);
DOT 1 (5950 2500);
DOT 1 (5950 2400);
DOT 1 (5950 2350);
DOT 1 (5950 2300);
DOT 1 (5950 2200);
DOT 1 (5950 2250);
DOT 1 (5950 2150);
DOT 1 (5950 2100);
DOT 1 (5950 2050);
DOT 1 (5950 2000);
DOT 1 (5950 1950);
DOT 1 (5950 1900);
DOT 1 (5950 1850);
DOT 1 (5950 1800);
DOT 1 (5950 1750);
DOT 1 (5950 1700);
DOT 1 (5950 1650);
DOT 1 (5950 1550);
DOT 1 (5950 1600);
DOT 1 (5950 1500);
DOT 1 (5950 1450);
DOT 1 (5950 1400);
DOT 1 (5950 1300);
DOT 1 (5950 1350);
DOT 1 (5950 1250);
DOT 1 (5950 1200);
DOT 1 (5950 1150);
DOT 1 (5950 1100);
DOT 1 (5950 1050);
DOT 1 (5950 1000);
DOT 1 (5950 950);
DOT 1 (5950 900);
DOT 1 (4550 3150);
DOT 1 (4550 3100);
DOT 1 (4550 3050);
DOT 1 (4550 2950);
DOT 1 (4550 3000);
DOT 1 (4550 2900);
DOT 1 (4550 2850);
DOT 1 (4550 2800);
DOT 1 (4550 2650);
DOT 1 (4550 2600);
DOT 1 (4550 2500);
DOT 1 (4550 2450);
DOT 1 (4550 2400);
DOT 1 (4550 2350);
DOT 1 (4550 2300);
DOT 1 (4550 2200);
DOT 1 (4550 2250);
DOT 1 (4550 2150);
DOT 1 (4550 2100);
DOT 1 (4550 2050);
DOT 1 (4100 2400);
DOT 1 (4550 2000);
DOT 1 (4550 1950);
DOT 1 (4550 1900);
DOT 1 (4550 1850);
DOT 1 (4550 1800);
DOT 1 (4550 1750);
DOT 1 (4550 1700);
DOT 1 (4550 1650);
DOT 1 (4550 1550);
DOT 1 (4550 1600);
DOT 1 (4550 1500);
DOT 1 (4550 1450);
DOT 1 (4550 1400);
DOT 1 (4550 1300);
DOT 1 (4550 1350);
DOT 1 (4550 1250);
DOT 1 (4550 1200);
DOT 1 (4550 1150);
DOT 1 (4550 1100);
DOT 1 (4550 1050);
DOT 1 (4550 1000);
DOT 1 (4550 900);
DOT 1 (4550 950);
DOT 1 (2700 2350);
DOT 1 (2700 2300);
DOT 1 (2700 2250);
DOT 1 (2700 2100);
DOT 1 (2700 1950);
DOT 1 (2700 1800);
DOT 1 (2700 1850);
DOT 1 (2700 1750);
DOT 1 (2700 1700);
DOT 1 (2700 1650);
DOT 1 (2700 1550);
DOT 1 (2700 1600);
DOT 1 (2700 1500);
DOT 1 (2700 1450);
DOT 1 (2700 1400);
DOT 1 (2700 1300);
DOT 1 (2700 1250);
DOT 1 (2700 1200);
DOT 1 (2700 1100);
DOT 1 (2700 1050);
DOT 1 (2700 1000);
DOT 1 (2700 950);
DOT 1 (2700 850);
DOT 1 (2700 800);
DOT 1 (2700 750);
DOT 1 (-1200 1600);
DOT 1 (2700 2400);
DOT 1 (2700 1350);
DOT 1 (2700 1900);
DOT 1 (2700 900);
DOT 1 (4550 2550);
DOT 1 (2700 1150);
FORCENOTE
PVDDQ (SINGLE SIDE) CAP: 10UF X1, 22UF X50
(100 850) 0;
DISPLAY LEFT (100 850);
DISPLAY 1.021277 (100 850);
PAINT PURPLE (100 850);
FORCENOTE
PVTT CAP: 100UF X2, 47UF X1
(100 900) 0;
DISPLAY LEFT (100 900);
DISPLAY 1.021277 (100 900);
PAINT PURPLE (100 900);
FORCENOTE
PVPP CAP: 10UF X12
(100 950) 0;
DISPLAY LEFT (100 950);
DISPLAY 1.021277 (100 950);
PAINT PURPLE (100 950);
FORCENOTE
CAP BETWEEN DIMM
(100 1025) 0;
DISPLAY LEFT (100 1025);
DISPLAY 1.276596 (100 1025);
PAINT PURPLE (100 1025);
FORCENOTE
PVDDQ (DOUBLE SIDE) CAP: 100UF X8, 47UF X41
(100 800) 0;
DISPLAY LEFT (100 800);
DISPLAY 1.021277 (100 800);
PAINT PURPLE (100 800);
FORCENOTE
SMBUS ADDR: 0XA2
(-1820 816) 0;
DISPLAY LEFT (-1820 816);
DISPLAY 1.957447 (-1820 816);
PAINT PURPLE (-1820 816);
FORCENOTE
PLACE CAP NEAR DIMM CONNECTOR
(-1788 1052) 0;
DISPLAY LEFT (-1788 1052);
DISPLAY 1.595745 (-1788 1052);
PAINT PURPLE (-1788 1052);
QUIT
